G04 ================== begin FILE IDENTIFICATION RECORD ==================*
G04 Layout Name:  D:/<user>/Wistron_project/16342-2/gbr/16342-2.brd*
G04 Film Name:    TMASK*
G04 File Format:  Gerber RS274X*
G04 File Origin:  Cadence Allegro 16.5-S056*
G04 Origin Date:  Mon Aug 07 11:24:20 2017*
G04 *
G04 Layer:  VIA CLASS/SOLDERMASK_TOP*
G04 Layer:  PIN/SOLDERMASK_TOP*
G04 Layer:  PACKAGE GEOMETRY/SOLDERMASK_TOP*
G04 Layer:  DRAWING FORMAT/LAYER_PCB_STORY*
G04 Layer:  DRAWING FORMAT/LAYER_SOLDER_T*
G04 Layer:  BOARD GEOMETRY/SOLDERMASK_TOP*
G04 *
G04 Offset:    (0.00 0.00)*
G04 Mirror:    No*
G04 Mode:      Positive*
G04 Rotation:  0*
G04 FullContactRelief:  No*
G04 UndefLineWidth:     6.00*
G04 ================== end FILE IDENTIFICATION RECORD ====================*
%FSLAX35Y35*MOIN*%
%IR0*IPPOS*OFA0.00000B0.00000*MIA0B0*SFA1.00000B1.00000*%
%AMMACRO57*
4,1,40,.013,.017,
-.013,.017,
-.013695,.016939,
-.014368,.016759,
-.015,.016464,
-.015571,.016064,
-.016064,.015571,
-.016464,.015,
-.016759,.014368,
-.016939,.013695,
-.017,.013,
-.017,-.013,
-.016939,-.013695,
-.016759,-.014368,
-.016464,-.015,
-.016064,-.015571,
-.015571,-.016064,
-.015,-.016464,
-.014368,-.016759,
-.013695,-.016939,
-.013,-.017,
.013,-.017,
.013695,-.016939,
.014368,-.016759,
.015,-.016464,
.015571,-.016064,
.016064,-.015571,
.016464,-.015,
.016759,-.014368,
.016939,-.013695,
.017,-.013,
.017,.013,
.016939,.013695,
.016759,.014368,
.016464,.015,
.016064,.015571,
.015571,.016064,
.015,.016464,
.014368,.016759,
.013695,.016939,
.013,.017,
0.0*
%
%ADD57MACRO57*%
%AMMACRO15*
4,1,40,.017,-.013,
.017,.013,
.016939,.013695,
.016759,.014368,
.016464,.015,
.016064,.015571,
.015571,.016064,
.015,.016464,
.014368,.016759,
.013695,.016939,
.013,.017,
-.013,.017,
-.013695,.016939,
-.014368,.016759,
-.015,.016464,
-.015571,.016064,
-.016064,.015571,
-.016464,.015,
-.016759,.014368,
-.016939,.013695,
-.017,.013,
-.017,-.013,
-.016939,-.013695,
-.016759,-.014368,
-.016464,-.015,
-.016064,-.015571,
-.015571,-.016064,
-.015,-.016464,
-.014368,-.016759,
-.013695,-.016939,
-.013,-.017,
.013,-.017,
.013695,-.016939,
.014368,-.016759,
.015,-.016464,
.015571,-.016064,
.016064,-.015571,
.016464,-.015,
.016759,-.014368,
.016939,-.013695,
.017,-.013,
0.0*
%
%ADD15MACRO15*%
%AMMACRO89*
4,1,40,.008,.009,
.008695,.008939,
.009368,.008759,
.01,.008464,
.010571,.008064,
.011064,.007571,
.011464,.007,
.011759,.006368,
.011939,.005695,
.012,.005,
.012,-.005,
.011939,-.005695,
.011759,-.006368,
.011464,-.007,
.011064,-.007571,
.010571,-.008064,
.01,-.008464,
.009368,-.008759,
.008695,-.008939,
.008,-.009,
-.008,-.009,
-.008695,-.008939,
-.009368,-.008759,
-.01,-.008464,
-.010571,-.008064,
-.011064,-.007571,
-.011464,-.007,
-.011759,-.006368,
-.011939,-.005695,
-.012,-.005,
-.012,.005,
-.011939,.005695,
-.011759,.006368,
-.011464,.007,
-.011064,.007571,
-.010571,.008064,
-.01,.008464,
-.009368,.008759,
-.008695,.008939,
-.008,.009,
.008,.009,
0.0*
%
%ADD89MACRO89*%
%ADD73O,.06X.111*%
%AMMACRO69*
4,1,15,-.0275,-.115,
-.0275,.02323,
-.02431,.026923,
-.021809,.031114,
-.020074,.035675,
-.019157,.040469,
-.019087,.045348,
-.019865,.050166,
-.021468,.054776,
-.023847,.059037,
-.02693,.06282,
-.0275,.06339,
-.0275,.115,
.0275,.115,
.0275,-.115,
-.0275,-.115,
0.0*
%
%ADD69MACRO69*%
%ADD116R,.01X.007*%
%ADD19C,.02*%
%ADD90C,.03*%
%ADD34C,.022*%
%ADD124C,.05*%
%ADD59C,.032*%
%ADD25C,.014*%
%ADD72C,.042*%
%ADD119R,.047X.108*%
%ADD82C,.034*%
%ADD55C,.016*%
%ADD120C,.044*%
%ADD26C,.026*%
%ADD20C,.08*%
%ADD123C,.063*%
%ADD46C,.028*%
%ADD16C,.056*%
%ADD80C,.048*%
%ADD105C,.094*%
%ADD21C,.086*%
%ADD110R,.062X.062*%
%AMMACRO68*
4,1,40,.0225,-.007,
.022378,-.008389,
.022018,-.009736,
.021428,-.011,
.020628,-.012142,
.019642,-.013128,
.0185,-.013928,
.017236,-.014518,
.015889,-.014878,
.0145,-.015,
-.0145,-.015,
-.015889,-.014878,
-.017236,-.014518,
-.0185,-.013928,
-.019642,-.013128,
-.020628,-.012142,
-.021428,-.011,
-.022018,-.009736,
-.022378,-.008389,
-.0225,-.007,
-.0225,.007,
-.022378,.008389,
-.022018,.009736,
-.021428,.011,
-.020628,.012142,
-.019642,.013128,
-.0185,.013928,
-.017236,.014518,
-.015889,.014878,
-.0145,.015,
.0145,.015,
.015889,.014878,
.017236,.014518,
.0185,.013928,
.019642,.013128,
.020628,.012142,
.021428,.011,
.022018,.009736,
.022378,.008389,
.0225,.007,
.0225,-.007,
0.0*
%
%ADD68MACRO68*%
%ADD104C,.097*%
%AMMACRO88*
4,1,40,-.007,-.0225,
-.008389,-.022378,
-.009736,-.022018,
-.011,-.021428,
-.012142,-.020628,
-.013128,-.019642,
-.013928,-.0185,
-.014518,-.017236,
-.014878,-.015889,
-.015,-.0145,
-.015,.0145,
-.014878,.015889,
-.014518,.017236,
-.013928,.0185,
-.013128,.019642,
-.012142,.020628,
-.011,.021428,
-.009736,.022018,
-.008389,.022378,
-.007,.0225,
.007,.0225,
.008389,.022378,
.009736,.022018,
.011,.021428,
.012142,.020628,
.013128,.019642,
.013928,.0185,
.014518,.017236,
.014878,.015889,
.015,.0145,
.015,-.0145,
.014878,-.015889,
.014518,-.017236,
.013928,-.0185,
.013128,-.019642,
.012142,-.020628,
.011,-.021428,
.009736,-.022018,
.008389,-.022378,
.007,-.0225,
-.007,-.0225,
0.0*
%
%ADD88MACRO88*%
%AMMACRO37*
4,1,40,.011,-.007,
.011,.007,
.010939,.007695,
.010759,.008368,
.010464,.009,
.010064,.009571,
.009571,.010064,
.009,.010464,
.008368,.010759,
.007695,.010939,
.007,.011,
-.007,.011,
-.007695,.010939,
-.008368,.010759,
-.009,.010464,
-.009571,.010064,
-.010064,.009571,
-.010464,.009,
-.010759,.008368,
-.010939,.007695,
-.011,.007,
-.011,-.007,
-.010939,-.007695,
-.010759,-.008368,
-.010464,-.009,
-.010064,-.009571,
-.009571,-.010064,
-.009,-.010464,
-.008368,-.010759,
-.007695,-.010939,
-.007,-.011,
.007,-.011,
.007695,-.010939,
.008368,-.010759,
.009,-.010464,
.009571,-.010064,
.010064,-.009571,
.010464,-.009,
.010759,-.008368,
.010939,-.007695,
.011,-.007,
0.0*
%
%ADD37MACRO37*%
%AMMACRO12*
4,1,40,.007,.011,
-.007,.011,
-.007695,.010939,
-.008368,.010759,
-.009,.010464,
-.009571,.010064,
-.010064,.009571,
-.010464,.009,
-.010759,.008368,
-.010939,.007695,
-.011,.007,
-.011,-.007,
-.010939,-.007695,
-.010759,-.008368,
-.010464,-.009,
-.010064,-.009571,
-.009571,-.010064,
-.009,-.010464,
-.008368,-.010759,
-.007695,-.010939,
-.007,-.011,
.007,-.011,
.007695,-.010939,
.008368,-.010759,
.009,-.010464,
.009571,-.010064,
.010064,-.009571,
.010464,-.009,
.010759,-.008368,
.010939,-.007695,
.011,-.007,
.011,.007,
.010939,.007695,
.010759,.008368,
.010464,.009,
.010064,.009571,
.009571,.010064,
.009,.010464,
.008368,.010759,
.007695,.010939,
.007,.011,
0.0*
%
%ADD12MACRO12*%
%AMMACRO28*
4,1,40,-.012,.008,
-.012,-.008,
-.011939,-.008695,
-.011759,-.009368,
-.011464,-.01,
-.011064,-.010571,
-.010571,-.011064,
-.01,-.011464,
-.009368,-.011759,
-.008695,-.011939,
-.008,-.012,
.008,-.012,
.008695,-.011939,
.009368,-.011759,
.01,-.011464,
.010571,-.011064,
.011064,-.010571,
.011464,-.01,
.011759,-.009368,
.011939,-.008695,
.012,-.008,
.012,.008,
.011939,.008695,
.011759,.009368,
.011464,.01,
.011064,.010571,
.010571,.011064,
.01,.011464,
.009368,.011759,
.008695,.011939,
.008,.012,
-.008,.012,
-.008695,.011939,
-.009368,.011759,
-.01,.011464,
-.010571,.011064,
-.011064,.010571,
-.011464,.01,
-.011759,.009368,
-.011939,.008695,
-.012,.008,
0.0*
%
%ADD28MACRO28*%
%AMMACRO42*
4,1,40,.008,.012,
-.008,.012,
-.008695,.011939,
-.009368,.011759,
-.01,.011464,
-.010571,.011064,
-.011064,.010571,
-.011464,.01,
-.011759,.009368,
-.011939,.008695,
-.012,.008,
-.012,-.008,
-.011939,-.008695,
-.011759,-.009368,
-.011464,-.01,
-.011064,-.010571,
-.010571,-.011064,
-.01,-.011464,
-.009368,-.011759,
-.008695,-.011939,
-.008,-.012,
.008,-.012,
.008695,-.011939,
.009368,-.011759,
.01,-.011464,
.010571,-.011064,
.011064,-.010571,
.011464,-.01,
.011759,-.009368,
.011939,-.008695,
.012,-.008,
.012,.008,
.011939,.008695,
.011759,.009368,
.011464,.01,
.011064,.010571,
.010571,.011064,
.01,.011464,
.009368,.011759,
.008695,.011939,
.008,.012,
0.0*
%
%ADD42MACRO42*%
%AMMACRO127*
4,1,6,.0135,-.025,
-.0065,-.005,
-.0135,-.005,
-.0135,.005,
-.0065,.005,
.0135,.025,
.0135,-.025,
0.0*
%
%ADD127MACRO127*%
%AMMACRO65*
4,1,40,-.013,-.017,
.013,-.017,
.013695,-.016939,
.014368,-.016759,
.015,-.016464,
.015571,-.016064,
.016064,-.015571,
.016464,-.015,
.016759,-.014368,
.016939,-.013695,
.017,-.013,
.017,.013,
.016939,.013695,
.016759,.014368,
.016464,.015,
.016064,.015571,
.015571,.016064,
.015,.016464,
.014368,.016759,
.013695,.016939,
.013,.017,
-.013,.017,
-.013695,.016939,
-.014368,.016759,
-.015,.016464,
-.015571,.016064,
-.016064,.015571,
-.016464,.015,
-.016759,.014368,
-.016939,.013695,
-.017,.013,
-.017,-.013,
-.016939,-.013695,
-.016759,-.014368,
-.016464,-.015,
-.016064,-.015571,
-.015571,-.016064,
-.015,-.016464,
-.014368,-.016759,
-.013695,-.016939,
-.013,-.017,
0.0*
%
%ADD65MACRO65*%
%AMMACRO114*
4,1,6,-.025,-.0135,
-.005,.0065,
-.005,.0135,
.005,.0135,
.005,.0065,
.025,-.0135,
-.025,-.0135,
0.0*
%
%ADD114MACRO114*%
%AMMACRO77*
4,1,40,-.009,.008,
-.008939,.008695,
-.008759,.009368,
-.008464,.01,
-.008064,.010571,
-.007571,.011064,
-.007,.011464,
-.006368,.011759,
-.005695,.011939,
-.005,.012,
.005,.012,
.005695,.011939,
.006368,.011759,
.007,.011464,
.007571,.011064,
.008064,.010571,
.008464,.01,
.008759,.009368,
.008939,.008695,
.009,.008,
.009,-.008,
.008939,-.008695,
.008759,-.009368,
.008464,-.01,
.008064,-.010571,
.007571,-.011064,
.007,-.011464,
.006368,-.011759,
.005695,-.011939,
.005,-.012,
-.005,-.012,
-.005695,-.011939,
-.006368,-.011759,
-.007,-.011464,
-.007571,-.011064,
-.008064,-.010571,
-.008464,-.01,
-.008759,-.009368,
-.008939,-.008695,
-.009,-.008,
-.009,.008,
0.0*
%
%ADD77MACRO77*%
%AMMACRO47*
4,1,40,-.017,.013,
-.017,-.013,
-.016939,-.013695,
-.016759,-.014368,
-.016464,-.015,
-.016064,-.015571,
-.015571,-.016064,
-.015,-.016464,
-.014368,-.016759,
-.013695,-.016939,
-.013,-.017,
.013,-.017,
.013695,-.016939,
.014368,-.016759,
.015,-.016464,
.015571,-.016064,
.016064,-.015571,
.016464,-.015,
.016759,-.014368,
.016939,-.013695,
.017,-.013,
.017,.013,
.016939,.013695,
.016759,.014368,
.016464,.015,
.016064,.015571,
.015571,.016064,
.015,.016464,
.014368,.016759,
.013695,.016939,
.013,.017,
-.013,.017,
-.013695,.016939,
-.014368,.016759,
-.015,.016464,
-.015571,.016064,
-.016064,.015571,
-.016464,.015,
-.016759,.014368,
-.016939,.013695,
-.017,.013,
0.0*
%
%ADD47MACRO47*%
%AMMACRO93*
4,1,40,.008,.009,
.008695,.008939,
.009368,.008759,
.01,.008464,
.010571,.008064,
.011064,.007571,
.011464,.007,
.011759,.006368,
.011939,.005695,
.012,.005,
.012,-.005,
.011939,-.005695,
.011759,-.006368,
.011464,-.007,
.011064,-.007571,
.010571,-.008064,
.01,-.008464,
.009368,-.008759,
.008695,-.008939,
.008,-.009,
-.008,-.009,
-.008695,-.008939,
-.009368,-.008759,
-.01,-.008464,
-.010571,-.008064,
-.011064,-.007571,
-.011464,-.007,
-.011759,-.006368,
-.011939,-.005695,
-.012,-.005,
-.012,.005,
-.011939,.005695,
-.011759,.006368,
-.011464,.007,
-.011064,.007571,
-.010571,.008064,
-.01,.008464,
-.009368,.008759,
-.008695,.008939,
-.008,.009,
.008,.009,
0.0*
%
%ADD93MACRO93*%
%AMMACRO53*
4,1,6,.005,.0135,
.005,.0065,
.025,-.0135,
-.025,-.0135,
-.005,.0065,
-.005,.0135,
.005,.0135,
0.0*
%
%ADD53MACRO53*%
%AMMACRO38*
4,1,40,.011,-.007,
.011,.007,
.010939,.007695,
.010759,.008368,
.010464,.009,
.010064,.009571,
.009571,.010064,
.009,.010464,
.008368,.010759,
.007695,.010939,
.007,.011,
-.007,.011,
-.007695,.010939,
-.008368,.010759,
-.009,.010464,
-.009571,.010064,
-.010064,.009571,
-.010464,.009,
-.010759,.008368,
-.010939,.007695,
-.011,.007,
-.011,-.007,
-.010939,-.007695,
-.010759,-.008368,
-.010464,-.009,
-.010064,-.009571,
-.009571,-.010064,
-.009,-.010464,
-.008368,-.010759,
-.007695,-.010939,
-.007,-.011,
.007,-.011,
.007695,-.010939,
.008368,-.010759,
.009,-.010464,
.009571,-.010064,
.010064,-.009571,
.010464,-.009,
.010759,-.008368,
.010939,-.007695,
.011,-.007,
0.0*
%
%ADD38MACRO38*%
%AMMACRO13*
4,1,40,.007,.011,
-.007,.011,
-.007695,.010939,
-.008368,.010759,
-.009,.010464,
-.009571,.010064,
-.010064,.009571,
-.010464,.009,
-.010759,.008368,
-.010939,.007695,
-.011,.007,
-.011,-.007,
-.010939,-.007695,
-.010759,-.008368,
-.010464,-.009,
-.010064,-.009571,
-.009571,-.010064,
-.009,-.010464,
-.008368,-.010759,
-.007695,-.010939,
-.007,-.011,
.007,-.011,
.007695,-.010939,
.008368,-.010759,
.009,-.010464,
.009571,-.010064,
.010064,-.009571,
.010464,-.009,
.010759,-.008368,
.010939,-.007695,
.011,-.007,
.011,.007,
.010939,.007695,
.010759,.008368,
.010464,.009,
.010064,.009571,
.009571,.010064,
.009,.010464,
.008368,.010759,
.007695,.010939,
.007,.011,
0.0*
%
%ADD13MACRO13*%
%AMMACRO27*
4,1,40,-.012,.008,
-.012,-.008,
-.011939,-.008695,
-.011759,-.009368,
-.011464,-.01,
-.011064,-.010571,
-.010571,-.011064,
-.01,-.011464,
-.009368,-.011759,
-.008695,-.011939,
-.008,-.012,
.008,-.012,
.008695,-.011939,
.009368,-.011759,
.01,-.011464,
.010571,-.011064,
.011064,-.010571,
.011464,-.01,
.011759,-.009368,
.011939,-.008695,
.012,-.008,
.012,.008,
.011939,.008695,
.011759,.009368,
.011464,.01,
.011064,.010571,
.010571,.011064,
.01,.011464,
.009368,.011759,
.008695,.011939,
.008,.012,
-.008,.012,
-.008695,.011939,
-.009368,.011759,
-.01,.011464,
-.010571,.011064,
-.011064,.010571,
-.011464,.01,
-.011759,.009368,
-.011939,.008695,
-.012,.008,
0.0*
%
%ADD27MACRO27*%
%AMMACRO41*
4,1,40,.008,.012,
-.008,.012,
-.008695,.011939,
-.009368,.011759,
-.01,.011464,
-.010571,.011064,
-.011064,.010571,
-.011464,.01,
-.011759,.009368,
-.011939,.008695,
-.012,.008,
-.012,-.008,
-.011939,-.008695,
-.011759,-.009368,
-.011464,-.01,
-.011064,-.010571,
-.010571,-.011064,
-.01,-.011464,
-.009368,-.011759,
-.008695,-.011939,
-.008,-.012,
.008,-.012,
.008695,-.011939,
.009368,-.011759,
.01,-.011464,
.010571,-.011064,
.011064,-.010571,
.011464,-.01,
.011759,-.009368,
.011939,-.008695,
.012,-.008,
.012,.008,
.011939,.008695,
.011759,.009368,
.011464,.01,
.011064,.010571,
.010571,.011064,
.01,.011464,
.009368,.011759,
.008695,.011939,
.008,.012,
0.0*
%
%ADD41MACRO41*%
%AMMACRO66*
4,1,40,-.013,-.017,
.013,-.017,
.013695,-.016939,
.014368,-.016759,
.015,-.016464,
.015571,-.016064,
.016064,-.015571,
.016464,-.015,
.016759,-.014368,
.016939,-.013695,
.017,-.013,
.017,.013,
.016939,.013695,
.016759,.014368,
.016464,.015,
.016064,.015571,
.015571,.016064,
.015,.016464,
.014368,.016759,
.013695,.016939,
.013,.017,
-.013,.017,
-.013695,.016939,
-.014368,.016759,
-.015,.016464,
-.015571,.016064,
-.016064,.015571,
-.016464,.015,
-.016759,.014368,
-.016939,.013695,
-.017,.013,
-.017,-.013,
-.016939,-.013695,
-.016759,-.014368,
-.016464,-.015,
-.016064,-.015571,
-.015571,-.016064,
-.015,-.016464,
-.014368,-.016759,
-.013695,-.016939,
-.013,-.017,
0.0*
%
%ADD66MACRO66*%
%AMMACRO76*
4,1,40,.009,-.008,
.008939,-.008695,
.008759,-.009368,
.008464,-.01,
.008064,-.010571,
.007571,-.011064,
.007,-.011464,
.006368,-.011759,
.005695,-.011939,
.005,-.012,
-.005,-.012,
-.005695,-.011939,
-.006368,-.011759,
-.007,-.011464,
-.007571,-.011064,
-.008064,-.010571,
-.008464,-.01,
-.008759,-.009368,
-.008939,-.008695,
-.009,-.008,
-.009,.008,
-.008939,.008695,
-.008759,.009368,
-.008464,.01,
-.008064,.010571,
-.007571,.011064,
-.007,.011464,
-.006368,.011759,
-.005695,.011939,
-.005,.012,
.005,.012,
.005695,.011939,
.006368,.011759,
.007,.011464,
.007571,.011064,
.008064,.010571,
.008464,.01,
.008759,.009368,
.008939,.008695,
.009,.008,
.009,-.008,
0.0*
%
%ADD76MACRO76*%
%AMMACRO48*
4,1,40,-.017,.013,
-.017,-.013,
-.016939,-.013695,
-.016759,-.014368,
-.016464,-.015,
-.016064,-.015571,
-.015571,-.016064,
-.015,-.016464,
-.014368,-.016759,
-.013695,-.016939,
-.013,-.017,
.013,-.017,
.013695,-.016939,
.014368,-.016759,
.015,-.016464,
.015571,-.016064,
.016064,-.015571,
.016464,-.015,
.016759,-.014368,
.016939,-.013695,
.017,-.013,
.017,.013,
.016939,.013695,
.016759,.014368,
.016464,.015,
.016064,.015571,
.015571,.016064,
.015,.016464,
.014368,.016759,
.013695,.016939,
.013,.017,
-.013,.017,
-.013695,.016939,
-.014368,.016759,
-.015,.016464,
-.015571,.016064,
-.016064,.015571,
-.016464,.015,
-.016759,.014368,
-.016939,.013695,
-.017,.013,
0.0*
%
%ADD48MACRO48*%
%AMMACRO92*
4,1,40,-.008,-.009,
-.008695,-.008939,
-.009368,-.008759,
-.01,-.008464,
-.010571,-.008064,
-.011064,-.007571,
-.011464,-.007,
-.011759,-.006368,
-.011939,-.005695,
-.012,-.005,
-.012,.005,
-.011939,.005695,
-.011759,.006368,
-.011464,.007,
-.011064,.007571,
-.010571,.008064,
-.01,.008464,
-.009368,.008759,
-.008695,.008939,
-.008,.009,
.008,.009,
.008695,.008939,
.009368,.008759,
.01,.008464,
.010571,.008064,
.011064,.007571,
.011464,.007,
.011759,.006368,
.011939,.005695,
.012,.005,
.012,-.005,
.011939,-.005695,
.011759,-.006368,
.011464,-.007,
.011064,-.007571,
.010571,-.008064,
.01,-.008464,
.009368,-.008759,
.008695,-.008939,
.008,-.009,
-.008,-.009,
0.0*
%
%ADD92MACRO92*%
%ADD96R,.012X.05*%
%ADD87R,.05X.012*%
%ADD75R,.06X.02*%
%ADD102R,.042X.012*%
%ADD100R,.012X.042*%
%ADD84R,.06X.012*%
%ADD17R,.022X.04*%
%ADD95R,.012X.043*%
%ADD86R,.043X.012*%
%ADD131R,.128X.13*%
%ADD121R,.012X.061*%
%ADD83R,.06X.014*%
%ADD79R,.081X.02*%
%ADD64R,.04X.016*%
%ADD52R,.044X.012*%
%ADD33R,.042X.014*%
%ADD32R,.014X.042*%
%ADD128R,.012X.044*%
%ADD118R,.014X.06*%
%ADD101R,.036X.012*%
%ADD99R,.012X.036*%
%ADD63R,.105X.128*%
%ADD122R,.016X.032*%
%ADD112R,.037X.012*%
%ADD111R,.012X.037*%
%ADD109R,.064X.03*%
%ADD107R,.03X.045*%
%ADD36C,.13*%
%ADD130R,.128X.133*%
%ADD40R,.066X.02*%
%ADD74O,.06X.084*%
%ADD18R,.05X.065*%
%ADD98R,.055X.042*%
%ADD91R,.026X.036*%
%ADD35O,.268X.134*%
%ADD39R,.065X.025*%
%ADD117O,.126X.189*%
%ADD108R,.09X.045*%
%ADD85R,.048X.016*%
%ADD78R,.025X.065*%
%ADD45R,.045X.055*%
%ADD103R,.13X.13*%
%ADD67R,.016X.048*%
%ADD44R,.055X.045*%
%ADD43R,.055X.036*%
%ADD61C,.256*%
%ADD129R,.09X.095*%
%ADD81R,.059X.045*%
%ADD60R,.024X.079*%
%ADD106R,.045X.059*%
%ADD97R,.152X.152*%
%AMMACRO71*
4,1,40,-.0225,.007,
-.022378,.008389,
-.022018,.009736,
-.021428,.011,
-.020628,.012142,
-.019642,.013128,
-.0185,.013928,
-.017236,.014518,
-.015889,.014878,
-.0145,.015,
.0145,.015,
.015889,.014878,
.017236,.014518,
.0185,.013928,
.019642,.013128,
.020628,.012142,
.021428,.011,
.022018,.009736,
.022378,.008389,
.0225,.007,
.0225,-.007,
.022378,-.008389,
.022018,-.009736,
.021428,-.011,
.020628,-.012142,
.019642,-.013128,
.0185,-.013928,
.017236,-.014518,
.015889,-.014878,
.0145,-.015,
-.0145,-.015,
-.015889,-.014878,
-.017236,-.014518,
-.0185,-.013928,
-.019642,-.013128,
-.020628,-.012142,
-.021428,-.011,
-.022018,-.009736,
-.022378,-.008389,
-.0225,-.007,
-.0225,.007,
0.0*
%
%ADD71MACRO71*%
%AMMACRO70*
4,1,40,.014,.008,
.014,-.008,
.013939,-.008695,
.013759,-.009368,
.013464,-.01,
.013064,-.010571,
.012571,-.011064,
.012,-.011464,
.011368,-.011759,
.010695,-.011939,
.01,-.012,
-.01,-.012,
-.010695,-.011939,
-.011368,-.011759,
-.012,-.011464,
-.012571,-.011064,
-.013064,-.010571,
-.013464,-.01,
-.013759,-.009368,
-.013939,-.008695,
-.014,-.008,
-.014,.008,
-.013939,.008695,
-.013759,.009368,
-.013464,.01,
-.013064,.010571,
-.012571,.011064,
-.012,.011464,
-.011368,.011759,
-.010695,.011939,
-.01,.012,
.01,.012,
.010695,.011939,
.011368,.011759,
.012,.011464,
.012571,.011064,
.013064,.010571,
.013464,.01,
.013759,.009368,
.013939,.008695,
.014,.008,
0.0*
%
%ADD70MACRO70*%
%ADD62R,.095X.09*%
%ADD22C,.375*%
%ADD115R,.083X.069*%
%ADD31R,.128X.128*%
%AMMACRO50*
4,1,40,-.008,-.012,
.008,-.012,
.008695,-.011939,
.009368,-.011759,
.01,-.011464,
.010571,-.011064,
.011064,-.010571,
.011464,-.01,
.011759,-.009368,
.011939,-.008695,
.012,-.008,
.012,.008,
.011939,.008695,
.011759,.009368,
.011464,.01,
.011064,.010571,
.010571,.011064,
.01,.011464,
.009368,.011759,
.008695,.011939,
.008,.012,
-.008,.012,
-.008695,.011939,
-.009368,.011759,
-.01,.011464,
-.010571,.011064,
-.011064,.010571,
-.011464,.01,
-.011759,.009368,
-.011939,.008695,
-.012,.008,
-.012,-.008,
-.011939,-.008695,
-.011759,-.009368,
-.011464,-.01,
-.011064,-.010571,
-.010571,-.011064,
-.01,-.011464,
-.009368,-.011759,
-.008695,-.011939,
-.008,-.012,
0.0*
%
%ADD50MACRO50*%
%AMMACRO30*
4,1,40,.012,-.008,
.012,.008,
.011939,.008695,
.011759,.009368,
.011464,.01,
.011064,.010571,
.010571,.011064,
.01,.011464,
.009368,.011759,
.008695,.011939,
.008,.012,
-.008,.012,
-.008695,.011939,
-.009368,.011759,
-.01,.011464,
-.010571,.011064,
-.011064,.010571,
-.011464,.01,
-.011759,.009368,
-.011939,.008695,
-.012,.008,
-.012,-.008,
-.011939,-.008695,
-.011759,-.009368,
-.011464,-.01,
-.011064,-.010571,
-.010571,-.011064,
-.01,-.011464,
-.009368,-.011759,
-.008695,-.011939,
-.008,-.012,
.008,-.012,
.008695,-.011939,
.009368,-.011759,
.01,-.011464,
.010571,-.011064,
.011064,-.010571,
.011464,-.01,
.011759,-.009368,
.011939,-.008695,
.012,-.008,
0.0*
%
%ADD30MACRO30*%
%AMMACRO23*
4,1,40,-.007,-.011,
.007,-.011,
.007695,-.010939,
.008368,-.010759,
.009,-.010464,
.009571,-.010064,
.010064,-.009571,
.010464,-.009,
.010759,-.008368,
.010939,-.007695,
.011,-.007,
.011,.007,
.010939,.007695,
.010759,.008368,
.010464,.009,
.010064,.009571,
.009571,.010064,
.009,.010464,
.008368,.010759,
.007695,.010939,
.007,.011,
-.007,.011,
-.007695,.010939,
-.008368,.010759,
-.009,.010464,
-.009571,.010064,
-.010064,.009571,
-.010464,.009,
-.010759,.008368,
-.010939,.007695,
-.011,.007,
-.011,-.007,
-.010939,-.007695,
-.010759,-.008368,
-.010464,-.009,
-.010064,-.009571,
-.009571,-.010064,
-.009,-.010464,
-.008368,-.010759,
-.007695,-.010939,
-.007,-.011,
0.0*
%
%ADD23MACRO23*%
%AMMACRO10*
4,1,40,-.011,.007,
-.011,-.007,
-.010939,-.007695,
-.010759,-.008368,
-.010464,-.009,
-.010064,-.009571,
-.009571,-.010064,
-.009,-.010464,
-.008368,-.010759,
-.007695,-.010939,
-.007,-.011,
.007,-.011,
.007695,-.010939,
.008368,-.010759,
.009,-.010464,
.009571,-.010064,
.010064,-.009571,
.010464,-.009,
.010759,-.008368,
.010939,-.007695,
.011,-.007,
.011,.007,
.010939,.007695,
.010759,.008368,
.010464,.009,
.010064,.009571,
.009571,.010064,
.009,.010464,
.008368,.010759,
.007695,.010939,
.007,.011,
-.007,.011,
-.007695,.010939,
-.008368,.010759,
-.009,.010464,
-.009571,.010064,
-.010064,.009571,
-.010464,.009,
-.010759,.008368,
-.010939,.007695,
-.011,.007,
0.0*
%
%ADD10MACRO10*%
%AMMACRO56*
4,1,40,.013,.017,
-.013,.017,
-.013695,.016939,
-.014368,.016759,
-.015,.016464,
-.015571,.016064,
-.016064,.015571,
-.016464,.015,
-.016759,.014368,
-.016939,.013695,
-.017,.013,
-.017,-.013,
-.016939,-.013695,
-.016759,-.014368,
-.016464,-.015,
-.016064,-.015571,
-.015571,-.016064,
-.015,-.016464,
-.014368,-.016759,
-.013695,-.016939,
-.013,-.017,
.013,-.017,
.013695,-.016939,
.014368,-.016759,
.015,-.016464,
.015571,-.016064,
.016064,-.015571,
.016464,-.015,
.016759,-.014368,
.016939,-.013695,
.017,-.013,
.017,.013,
.016939,.013695,
.016759,.014368,
.016464,.015,
.016064,.015571,
.015571,.016064,
.015,.016464,
.014368,.016759,
.013695,.016939,
.013,.017,
0.0*
%
%ADD56MACRO56*%
%AMMACRO54*
4,1,6,.025,.0135,
.005,-.0065,
.005,-.0135,
-.005,-.0135,
-.005,-.0065,
-.025,.0135,
.025,.0135,
0.0*
%
%ADD54MACRO54*%
%AMMACRO14*
4,1,40,.017,-.013,
.017,.013,
.016939,.013695,
.016759,.014368,
.016464,.015,
.016064,.015571,
.015571,.016064,
.015,.016464,
.014368,.016759,
.013695,.016939,
.013,.017,
-.013,.017,
-.013695,.016939,
-.014368,.016759,
-.015,.016464,
-.015571,.016064,
-.016064,.015571,
-.016464,.015,
-.016759,.014368,
-.016939,.013695,
-.017,.013,
-.017,-.013,
-.016939,-.013695,
-.016759,-.014368,
-.016464,-.015,
-.016064,-.015571,
-.015571,-.016064,
-.015,-.016464,
-.014368,-.016759,
-.013695,-.016939,
-.013,-.017,
.013,-.017,
.013695,-.016939,
.014368,-.016759,
.015,-.016464,
.015571,-.016064,
.016064,-.015571,
.016464,-.015,
.016759,-.014368,
.016939,-.013695,
.017,-.013,
0.0*
%
%ADD14MACRO14*%
%AMMACRO94*
4,1,40,-.008,-.009,
-.008695,-.008939,
-.009368,-.008759,
-.01,-.008464,
-.010571,-.008064,
-.011064,-.007571,
-.011464,-.007,
-.011759,-.006368,
-.011939,-.005695,
-.012,-.005,
-.012,.005,
-.011939,.005695,
-.011759,.006368,
-.011464,.007,
-.011064,.007571,
-.010571,.008064,
-.01,.008464,
-.009368,.008759,
-.008695,.008939,
-.008,.009,
.008,.009,
.008695,.008939,
.009368,.008759,
.01,.008464,
.010571,.008064,
.011064,.007571,
.011464,.007,
.011759,.006368,
.011939,.005695,
.012,.005,
.012,-.005,
.011939,-.005695,
.011759,-.006368,
.011464,-.007,
.011064,-.007571,
.010571,-.008064,
.01,-.008464,
.009368,-.008759,
.008695,-.008939,
.008,-.009,
-.008,-.009,
0.0*
%
%ADD94MACRO94*%
%AMMACRO126*
4,1,6,.0135,-.005,
.0065,-.005,
-.0135,-.025,
-.0135,.025,
.0065,.005,
.0135,.005,
.0135,-.005,
0.0*
%
%ADD126MACRO126*%
%AMMACRO113*
4,1,6,-.005,-.0135,
-.005,-.0065,
-.025,.0135,
.025,.0135,
.005,-.0065,
.005,-.0135,
-.005,-.0135,
0.0*
%
%ADD113MACRO113*%
%AMMACRO125*
4,1,20,.1075,.0635,
.1075,.049,
.118,.049,
.118,.0395,
.1075,.0395,
.1075,-.0395,
.118,-.0395,
.118,-.049,
.1075,-.049,
.1075,-.0635,
-.1075,-.0635,
-.1075,-.049,
-.118,-.049,
-.118,-.0395,
-.1075,-.0395,
-.1075,.0395,
-.118,.0395,
-.118,.049,
-.1075,.049,
-.1075,.0635,
.1075,.0635,
0.0*
%
%ADD125MACRO125*%
%AMMACRO51*
4,1,20,-.0635,.1075,
-.049,.1075,
-.049,.118,
-.0395,.118,
-.0395,.1075,
.0395,.1075,
.0395,.118,
.049,.118,
.049,.1075,
.0635,.1075,
.0635,-.1075,
.049,-.1075,
.049,-.118,
.0395,-.118,
.0395,-.1075,
-.0395,-.1075,
-.0395,-.118,
-.049,-.118,
-.049,-.1075,
-.0635,-.1075,
-.0635,.1075,
0.0*
%
%ADD51MACRO51*%
%AMMACRO58*
4,1,15,-.0275,-.115,
-.0275,.115,
.0275,.115,
.0275,.06339,
.02431,.059697,
.021809,.055506,
.020074,.050945,
.019157,.046151,
.019087,.041272,
.019865,.036454,
.021468,.031844,
.023847,.027583,
.02693,.0238,
.0275,.02323,
.0275,-.115,
-.0275,-.115,
0.0*
%
%ADD58MACRO58*%
%AMMACRO49*
4,1,40,-.008,-.012,
.008,-.012,
.008695,-.011939,
.009368,-.011759,
.01,-.011464,
.010571,-.011064,
.011064,-.010571,
.011464,-.01,
.011759,-.009368,
.011939,-.008695,
.012,-.008,
.012,.008,
.011939,.008695,
.011759,.009368,
.011464,.01,
.011064,.010571,
.010571,.011064,
.01,.011464,
.009368,.011759,
.008695,.011939,
.008,.012,
-.008,.012,
-.008695,.011939,
-.009368,.011759,
-.01,.011464,
-.010571,.011064,
-.011064,.010571,
-.011464,.01,
-.011759,.009368,
-.011939,.008695,
-.012,.008,
-.012,-.008,
-.011939,-.008695,
-.011759,-.009368,
-.011464,-.01,
-.011064,-.010571,
-.010571,-.011064,
-.01,-.011464,
-.009368,-.011759,
-.008695,-.011939,
-.008,-.012,
0.0*
%
%ADD49MACRO49*%
%AMMACRO29*
4,1,40,.012,-.008,
.012,.008,
.011939,.008695,
.011759,.009368,
.011464,.01,
.011064,.010571,
.010571,.011064,
.01,.011464,
.009368,.011759,
.008695,.011939,
.008,.012,
-.008,.012,
-.008695,.011939,
-.009368,.011759,
-.01,.011464,
-.010571,.011064,
-.011064,.010571,
-.011464,.01,
-.011759,.009368,
-.011939,.008695,
-.012,.008,
-.012,-.008,
-.011939,-.008695,
-.011759,-.009368,
-.011464,-.01,
-.011064,-.010571,
-.010571,-.011064,
-.01,-.011464,
-.009368,-.011759,
-.008695,-.011939,
-.008,-.012,
.008,-.012,
.008695,-.011939,
.009368,-.011759,
.01,-.011464,
.010571,-.011064,
.011064,-.010571,
.011464,-.01,
.011759,-.009368,
.011939,-.008695,
.012,-.008,
0.0*
%
%ADD29MACRO29*%
%AMMACRO24*
4,1,40,-.007,-.011,
.007,-.011,
.007695,-.010939,
.008368,-.010759,
.009,-.010464,
.009571,-.010064,
.010064,-.009571,
.010464,-.009,
.010759,-.008368,
.010939,-.007695,
.011,-.007,
.011,.007,
.010939,.007695,
.010759,.008368,
.010464,.009,
.010064,.009571,
.009571,.010064,
.009,.010464,
.008368,.010759,
.007695,.010939,
.007,.011,
-.007,.011,
-.007695,.010939,
-.008368,.010759,
-.009,.010464,
-.009571,.010064,
-.010064,.009571,
-.010464,.009,
-.010759,.008368,
-.010939,.007695,
-.011,.007,
-.011,-.007,
-.010939,-.007695,
-.010759,-.008368,
-.010464,-.009,
-.010064,-.009571,
-.009571,-.010064,
-.009,-.010464,
-.008368,-.010759,
-.007695,-.010939,
-.007,-.011,
0.0*
%
%ADD24MACRO24*%
%AMMACRO11*
4,1,40,-.011,.007,
-.011,-.007,
-.010939,-.007695,
-.010759,-.008368,
-.010464,-.009,
-.010064,-.009571,
-.009571,-.010064,
-.009,-.010464,
-.008368,-.010759,
-.007695,-.010939,
-.007,-.011,
.007,-.011,
.007695,-.010939,
.008368,-.010759,
.009,-.010464,
.009571,-.010064,
.010064,-.009571,
.010464,-.009,
.010759,-.008368,
.010939,-.007695,
.011,-.007,
.011,.007,
.010939,.007695,
.010759,.008368,
.010464,.009,
.010064,.009571,
.009571,.010064,
.009,.010464,
.008368,.010759,
.007695,.010939,
.007,.011,
-.007,.011,
-.007695,.010939,
-.008368,.010759,
-.009,.010464,
-.009571,.010064,
-.010064,.009571,
-.010464,.009,
-.010759,.008368,
-.010939,.007695,
-.011,.007,
0.0*
%
%ADD11MACRO11*%
%ADD132C,.006*%
G75*
%LPD*%
G75*
G36*
G01X535408Y30333D02*
Y21783D01*
X544358D01*
Y30333D01*
X535408D01*
G37*
G36*
G01Y41483D02*
Y32933D01*
X544358D01*
Y41483D01*
X535408D01*
G37*
G36*
G01X546958Y30333D02*
Y21783D01*
X555908D01*
Y30333D01*
X546958D01*
G37*
G36*
G01Y41483D02*
Y32933D01*
X555908D01*
Y41483D01*
X546958D01*
G37*
G54D100*
X463079Y45150D03*
X465047D03*
X467016D03*
X468984D03*
X470953D03*
X472921D03*
Y25650D03*
X470953D03*
X468984D03*
X467016D03*
X465047D03*
X463079D03*
G54D101*
X478050Y42290D03*
Y28510D03*
X457950D03*
Y42290D03*
X612110Y47920D03*
Y42014D03*
X599898D03*
Y47920D03*
G54D110*
X606004Y44967D03*
G54D111*
X605020Y51023D03*
X606988D03*
Y38911D03*
X605020D03*
G54D102*
X477750Y40321D03*
Y38353D03*
Y36384D03*
Y34416D03*
Y32447D03*
Y30479D03*
X458250D03*
Y32447D03*
Y34416D03*
Y36384D03*
Y38353D03*
Y40321D03*
G54D120*
X666929Y510236D03*
X765354D03*
G54D10*
X38500Y49800D03*
X48200Y675584D03*
X78268Y60055D03*
X104000Y478800D03*
X108500Y487300D03*
X104000D03*
X108277Y570651D03*
X111200Y709900D03*
X86028Y689739D03*
X81928Y689839D03*
X174588Y489713D03*
X187167Y502984D03*
X198700Y516900D03*
X203500D03*
X212600Y517000D03*
X141914Y519838D03*
X182648Y503054D03*
X204100Y638000D03*
X142572Y633732D03*
X150872D03*
X166500Y633800D03*
X157458Y633832D03*
X145279Y619170D03*
X172700Y622700D03*
X176800D03*
X180985D03*
X185085D03*
X189185D03*
X193285D03*
X149400Y623200D03*
X154300Y703515D03*
X168047Y705075D03*
X151749Y695715D03*
X164249D03*
X210123Y655596D03*
X267514Y540585D03*
X243700Y552100D03*
X229342Y514955D03*
X223400Y638000D03*
X238000Y621800D03*
X234000D03*
X221900Y623700D03*
X229952Y626430D03*
X225900Y623700D03*
X251900Y613400D03*
X243900D03*
X262823Y624696D03*
X236000Y639200D03*
X225984Y659043D03*
X258431Y704824D03*
X246700Y675900D03*
X247500Y702300D03*
X214723Y652096D03*
X343582Y178478D03*
X347882Y271078D03*
X346819Y520675D03*
X350400Y528500D03*
X341226Y528509D03*
X334827Y517153D03*
X304617Y589881D03*
X299000Y658100D03*
X289612Y661529D03*
X291700Y730200D03*
X287620Y730220D03*
X374883Y181153D03*
X359481Y484466D03*
X384300Y548400D03*
X361120Y585686D03*
X374600Y583400D03*
X464342Y53858D03*
X468400Y61300D03*
X472700Y61200D03*
X443489Y42401D03*
X594541Y29581D03*
X590347Y57307D03*
X703300Y21800D03*
X713200Y390800D03*
X712851Y474882D03*
X712000Y435400D03*
X718300Y390800D03*
X725200Y435400D03*
X754800Y527000D03*
X854596Y159135D03*
X841625Y177777D03*
X846077Y152224D03*
X838627Y378815D03*
X846456Y354057D03*
X834984Y371069D03*
X796100Y389800D03*
X801200D03*
X811099Y473779D03*
X794900Y434400D03*
X808100D03*
G54D103*
X468000Y35400D03*
G54D130*
X882622Y129353D03*
Y164275D03*
G54D112*
X612060Y45951D03*
Y43983D03*
X599948D03*
Y45951D03*
G54D121*
X714173Y501279D03*
X712205D03*
X710236D03*
X708268D03*
X706299D03*
X704330D03*
X702362D03*
X700393D03*
X698425D03*
X696456D03*
X694488D03*
X692519D03*
X690551D03*
X688582D03*
X686614D03*
X684645D03*
X682677D03*
X680708D03*
X678740D03*
X676771D03*
X674803D03*
X672834D03*
X670866D03*
X713189Y531004D03*
X711220D03*
X709252D03*
X707283D03*
X705315D03*
X703346D03*
X701378D03*
X699409D03*
X697441D03*
X695472D03*
X693504D03*
X691535D03*
X689567D03*
X687598D03*
X685630D03*
X683661D03*
X681693D03*
X679724D03*
X677756D03*
X675787D03*
X673819D03*
X671850D03*
X669882D03*
X785039Y501279D03*
X783070D03*
X781102D03*
X779133D03*
X777165D03*
X775196D03*
X773228D03*
X771259D03*
X769291D03*
X786023Y531004D03*
X784055D03*
X782086D03*
X780118D03*
X778149D03*
X776181D03*
X774212D03*
X772244D03*
X770275D03*
X768307D03*
X741732Y501279D03*
X739764D03*
X737795D03*
X735827D03*
X725984D03*
X724016D03*
X722047D03*
X720079D03*
X718110D03*
X716142D03*
X742716Y531004D03*
X740748D03*
X738779D03*
X736811D03*
X734842D03*
X725000D03*
X723031D03*
X721063D03*
X719094D03*
X717126D03*
X715157D03*
X840157Y501279D03*
X838189D03*
X836220D03*
X834252D03*
X824409D03*
X822441D03*
X820472D03*
X818504D03*
X816535D03*
X814567D03*
X812598D03*
X810630D03*
X808661D03*
X806693D03*
X804724D03*
X802755D03*
X800787D03*
X798818D03*
X796850D03*
X794881D03*
X792913D03*
X790944D03*
X788976D03*
X787007D03*
X841141Y531004D03*
X839173D03*
X837204D03*
X835236D03*
X833267D03*
X823425D03*
X821456D03*
X819488D03*
X817519D03*
X815551D03*
X813582D03*
X811614D03*
X809645D03*
X807677D03*
X805708D03*
X803740D03*
X801771D03*
X799803D03*
X797834D03*
X795866D03*
X793897D03*
X791929D03*
X789960D03*
X787992D03*
G54D11*
X38500Y53200D03*
X48200Y678984D03*
X78268Y63455D03*
X104000Y482200D03*
X108500Y490700D03*
X104000D03*
X108277Y574051D03*
X86028Y693139D03*
X81928Y693239D03*
X111200Y713300D03*
X174588Y493113D03*
X187167Y506384D03*
X198700Y520300D03*
X203500D03*
X212600Y520400D03*
X141914Y523238D03*
X182648Y506454D03*
X142572Y637132D03*
X150872D03*
X166500Y637200D03*
X157458Y637232D03*
X145279Y622570D03*
X172700Y626100D03*
X176800D03*
X180985D03*
X185085D03*
X189185D03*
X193285D03*
X149400Y626600D03*
X204100Y641400D03*
X154300Y706915D03*
X168047Y708475D03*
X151749Y699115D03*
X164249D03*
X210123Y658996D03*
X267514Y543985D03*
X243700Y555500D03*
X229342Y518355D03*
X238000Y625200D03*
X234000D03*
X221900Y627100D03*
X229952Y629830D03*
X225900Y627100D03*
X251900Y616800D03*
X243900D03*
X262823Y628096D03*
X236000Y642600D03*
X223400Y641400D03*
X225984Y662443D03*
X258431Y708224D03*
X246700Y679300D03*
X247500Y705700D03*
X214723Y655496D03*
X343582Y181878D03*
X347882Y274478D03*
X346819Y524075D03*
X350400Y531900D03*
X341226Y531909D03*
X334827Y520553D03*
X304617Y593281D03*
X299000Y661500D03*
X289612Y664929D03*
X291700Y733600D03*
X287620Y733620D03*
X374883Y184553D03*
X359481Y487866D03*
X384300Y551800D03*
X361120Y589086D03*
X374600Y586800D03*
X464342Y57258D03*
X443489Y45801D03*
X468400Y64700D03*
X472700Y64600D03*
X594541Y32981D03*
X590347Y60707D03*
X703300Y25200D03*
X713200Y394200D03*
X712851Y478282D03*
X712000Y438800D03*
X718300Y394200D03*
X725200Y438800D03*
X754800Y530400D03*
X854596Y162535D03*
X841625Y181177D03*
X846077Y155624D03*
X838627Y382215D03*
X846456Y357457D03*
X834984Y374469D03*
X796100Y393200D03*
X801200D03*
X811099Y477179D03*
X794900Y437800D03*
X808100D03*
G54D113*
X588647Y35057D03*
G54D122*
X775160Y23465D03*
X772600D03*
X770040D03*
Y31535D03*
X772600D03*
X775160D03*
G54D131*
X877456Y322390D03*
Y357012D03*
G54D104*
X488838Y137225D03*
G54D20*
X30900Y79600D03*
X81169Y734566D03*
X145053Y647840D03*
X271068Y529401D03*
X847271Y45720D03*
G54D132*
G01X-9023Y-84471D02*
X-8149Y-83596D01*
X-7494Y-82138D01*
X-7057Y-80095D01*
X-7494Y-78346D01*
X-8367Y-77179D01*
X-9896Y-76304D01*
X-15791D01*
Y-93804D01*
X-8586D01*
X-7057Y-92638D01*
X-6184Y-90887D01*
X-5747Y-88846D01*
X-6184Y-86804D01*
X-7494Y-85054D01*
X-9023Y-84471D01*
X-15791D01*
G01X3674Y-93804D02*
Y-82138D01*
G01Y-84471D02*
X4766Y-83304D01*
X5858Y-82429D01*
X7386Y-82138D01*
X8477Y-82429D01*
X9788Y-83304D01*
G01X19646Y-99054D02*
X20956Y-99637D01*
X22703Y-99054D01*
X23794Y-97888D01*
X24668Y-96429D01*
X25977Y-91763D01*
X28816Y-82138D01*
G01X21829D02*
X25977Y-91763D01*
G01X45224Y-83596D02*
X43696Y-82429D01*
X42386Y-82138D01*
X40639Y-82721D01*
X39329Y-83887D01*
X38456Y-85929D01*
X38237Y-87971D01*
X38456Y-90013D01*
X39329Y-91763D01*
X40639Y-93221D01*
X42386Y-93804D01*
X43914Y-93221D01*
X45224Y-92054D01*
G01X55956Y-85929D02*
X62943D01*
X62288Y-83887D01*
X61196Y-82721D01*
X59668Y-82138D01*
X58139Y-82429D01*
X56829Y-83304D01*
X55956Y-85346D01*
X55519Y-87096D01*
Y-88846D01*
X55956Y-90596D01*
X57048Y-92346D01*
X58358Y-93512D01*
X59886Y-93804D01*
X61414Y-93221D01*
X62943Y-91471D01*
G01X99034Y-77763D02*
X97724Y-76887D01*
X96196Y-76304D01*
X94449D01*
X92484Y-77179D01*
X90956Y-78637D01*
X89864Y-80388D01*
X88991Y-83304D01*
X88772Y-85929D01*
X89209Y-88554D01*
X89864Y-90304D01*
X91174Y-92054D01*
X92703Y-93221D01*
X94231Y-93804D01*
X95759D01*
X97288Y-93221D01*
X98598Y-92346D01*
X99690Y-91180D01*
G01X115661Y-93804D02*
Y-82138D01*
G01Y-84179D02*
X114788Y-83013D01*
X113477Y-82429D01*
X111949Y-82138D01*
X110421Y-82721D01*
X109111Y-83887D01*
X108237Y-85637D01*
X107801Y-87971D01*
X108237Y-90304D01*
X109111Y-92054D01*
X110421Y-93221D01*
X111949Y-93804D01*
X113477Y-93512D01*
X114788Y-92638D01*
X115661Y-91471D01*
G01X125519Y-93804D02*
Y-82138D01*
G01Y-85054D02*
X126393Y-83596D01*
X127703Y-82429D01*
X129449Y-82138D01*
X130977Y-82429D01*
X132288Y-83596D01*
X132943Y-85637D01*
Y-93804D01*
G01X142146Y-99054D02*
X143456Y-99637D01*
X145203Y-99054D01*
X146294Y-97888D01*
X147168Y-96429D01*
X148477Y-91763D01*
X151316Y-82138D01*
G01X144329D02*
X148477Y-91763D01*
G01X164231Y-93804D02*
X162921Y-93512D01*
X161611Y-92346D01*
X160737Y-90304D01*
X160301Y-87971D01*
X160737Y-85637D01*
X161611Y-83596D01*
X162921Y-82429D01*
X164231Y-82138D01*
X165541Y-82429D01*
X166851Y-83596D01*
X167724Y-85637D01*
X167943Y-87971D01*
X167724Y-90304D01*
X166851Y-92346D01*
X165541Y-93512D01*
X164231Y-93804D01*
G01X178019D02*
Y-82138D01*
G01Y-85054D02*
X178893Y-83596D01*
X180203Y-82429D01*
X181949Y-82138D01*
X183477Y-82429D01*
X184788Y-83596D01*
X185443Y-85637D01*
Y-93804D01*
G01X214111Y-76304D02*
X219351D01*
G01X216731D02*
Y-93804D01*
G01X214111D02*
X219351D01*
G01X234231D02*
X232484Y-93512D01*
X230956Y-92346D01*
X229646Y-90596D01*
X228772Y-88554D01*
X228336Y-86221D01*
Y-83887D01*
X228772Y-81554D01*
X229646Y-79512D01*
X230956Y-77763D01*
X232484Y-76596D01*
X234231Y-76304D01*
X235977Y-76596D01*
X237506Y-77763D01*
X238816Y-79512D01*
X239690Y-81554D01*
X240126Y-83887D01*
Y-86221D01*
X239690Y-88554D01*
X238816Y-90596D01*
X237506Y-92346D01*
X235977Y-93512D01*
X234231Y-93804D01*
G01X246054D02*
Y-76304D01*
X251731Y-90887D01*
X257408Y-76304D01*
Y-93804D01*
G01X285639Y-99637D02*
X283456Y-96721D01*
X282364Y-93804D01*
Y-82138D01*
X283456Y-79221D01*
X285639Y-76304D01*
G01X298554Y-93804D02*
Y-76304D01*
X304231Y-90887D01*
X309908Y-76304D01*
Y-93804D01*
G01X321731Y-94387D02*
X321294Y-94096D01*
Y-93512D01*
X321731Y-93221D01*
X322168Y-93512D01*
Y-94096D01*
X321731Y-94387D01*
G01X335083Y-79221D02*
X336393Y-77471D01*
X337921Y-76596D01*
X339668Y-76304D01*
X341851Y-76887D01*
X343379Y-78346D01*
X343816Y-80095D01*
X343598Y-81846D01*
X342724Y-83304D01*
X338358Y-86221D01*
X336393Y-88262D01*
X335083Y-91180D01*
X334646Y-93804D01*
X343816D01*
G01X374231D02*
X372921Y-93512D01*
X371611Y-92346D01*
X370737Y-90304D01*
X370301Y-87971D01*
X370737Y-85637D01*
X371611Y-83596D01*
X372921Y-82429D01*
X374231Y-82138D01*
X375541Y-82429D01*
X376851Y-83596D01*
X377724Y-85637D01*
X377943Y-87971D01*
X377724Y-90304D01*
X376851Y-92346D01*
X375541Y-93512D01*
X374231Y-93804D01*
G01X388019D02*
Y-82138D01*
G01Y-85054D02*
X388893Y-83596D01*
X390203Y-82429D01*
X391949Y-82138D01*
X393477Y-82429D01*
X394788Y-83596D01*
X395443Y-85637D01*
Y-93804D01*
G01X409231D02*
Y-76304D01*
G01X422146Y-99054D02*
X423456Y-99637D01*
X425203Y-99054D01*
X426294Y-97888D01*
X427168Y-96429D01*
X428477Y-91763D01*
X431316Y-82138D01*
G01X424329D02*
X428477Y-91763D01*
G01X445323Y-99637D02*
X447506Y-96721D01*
X448598Y-93804D01*
Y-82138D01*
X447506Y-79221D01*
X445323Y-76304D01*
G01X176054Y-48804D02*
Y-31304D01*
X181731Y-45887D01*
X187408Y-31304D01*
Y-48804D01*
G01X199231D02*
X197921Y-48512D01*
X196611Y-47346D01*
X195737Y-45304D01*
X195301Y-42971D01*
X195737Y-40637D01*
X196611Y-38596D01*
X197921Y-37429D01*
X199231Y-37138D01*
X200541Y-37429D01*
X201851Y-38596D01*
X202724Y-40637D01*
X202943Y-42971D01*
X202724Y-45304D01*
X201851Y-47346D01*
X200541Y-48512D01*
X199231Y-48804D01*
G01X220661Y-31304D02*
Y-48804D01*
G01Y-46180D02*
X219788Y-47638D01*
X218477Y-48512D01*
X216949Y-48804D01*
X215203Y-48221D01*
X213893Y-46763D01*
X213019Y-45013D01*
X212801Y-42971D01*
X213019Y-40929D01*
X213893Y-39179D01*
X215203Y-37721D01*
X216949Y-37138D01*
X218477Y-37429D01*
X219569Y-38013D01*
X220661Y-39179D01*
G01X230956Y-40929D02*
X237943D01*
X237288Y-38887D01*
X236196Y-37721D01*
X234668Y-37138D01*
X233139Y-37429D01*
X231829Y-38304D01*
X230956Y-40346D01*
X230519Y-42096D01*
Y-43846D01*
X230956Y-45596D01*
X232048Y-47346D01*
X233358Y-48512D01*
X234886Y-48804D01*
X236414Y-48221D01*
X237943Y-46471D01*
G01X251731Y-48804D02*
Y-31304D01*
G01X504231Y-93804D02*
Y-76304D01*
X501611Y-79804D01*
G01Y-93804D02*
X506851D01*
G01X517583Y-86513D02*
X519111Y-84471D01*
X520421Y-83304D01*
X522168Y-82721D01*
X523696Y-83304D01*
X524788Y-84471D01*
X525661Y-86221D01*
X525879Y-88262D01*
X525661Y-90013D01*
X524788Y-91763D01*
X523477Y-93221D01*
X521949Y-93804D01*
X520203Y-93221D01*
X518674Y-91471D01*
X517801Y-88846D01*
X517583Y-85929D01*
X518019Y-82138D01*
X518674Y-80095D01*
X519766Y-78054D01*
X521294Y-76596D01*
X522823Y-76304D01*
X524351Y-76887D01*
X525443Y-78346D01*
G01X534428Y-90304D02*
X535737Y-92346D01*
X537484Y-93512D01*
X539449Y-93804D01*
X541196Y-93512D01*
X542943Y-92054D01*
X544034Y-90304D01*
X544253Y-88554D01*
X543816Y-86513D01*
X542288Y-85054D01*
X540759Y-84471D01*
X538794D01*
G01X540759D02*
X542069Y-83596D01*
X543161Y-82138D01*
X543598Y-80388D01*
X543161Y-78637D01*
X542069Y-77179D01*
X540104Y-76304D01*
X538139Y-76596D01*
X536174Y-77763D01*
G01X559351Y-93804D02*
Y-76304D01*
X551272Y-88846D01*
X562190D01*
G01X570083Y-79221D02*
X571393Y-77471D01*
X572921Y-76596D01*
X574668Y-76304D01*
X576851Y-76887D01*
X578379Y-78346D01*
X578816Y-80095D01*
X578598Y-81846D01*
X577724Y-83304D01*
X573358Y-86221D01*
X571393Y-88262D01*
X570083Y-91180D01*
X569646Y-93804D01*
X578816D01*
G01X491114Y-48804D02*
Y-31304D01*
X496354D01*
X498101Y-32179D01*
X499411Y-34221D01*
X499848Y-36554D01*
X499411Y-38887D01*
X498319Y-40637D01*
X496354Y-41513D01*
X491114D01*
G01X517784Y-32763D02*
X516474Y-31887D01*
X514946Y-31304D01*
X513199D01*
X511234Y-32179D01*
X509706Y-33637D01*
X508614Y-35388D01*
X507741Y-38304D01*
X507522Y-40929D01*
X507959Y-43554D01*
X508614Y-45304D01*
X509924Y-47054D01*
X511453Y-48221D01*
X512981Y-48804D01*
X514509D01*
X516038Y-48221D01*
X517348Y-47346D01*
X518440Y-46180D01*
G01X532227Y-39471D02*
X533101Y-38596D01*
X533756Y-37138D01*
X534193Y-35095D01*
X533756Y-33346D01*
X532883Y-32179D01*
X531354Y-31304D01*
X525459D01*
Y-48804D01*
X532664D01*
X534193Y-47638D01*
X535066Y-45887D01*
X535503Y-43846D01*
X535066Y-41804D01*
X533756Y-40054D01*
X532227Y-39471D01*
X525459D01*
G01X541431Y-54637D02*
X554531D01*
G01X560459Y-48804D02*
Y-31304D01*
X570503Y-48804D01*
Y-31304D01*
G01X582981Y-48804D02*
X581234Y-48512D01*
X579706Y-47346D01*
X578396Y-45596D01*
X577522Y-43554D01*
X577086Y-41221D01*
Y-38887D01*
X577522Y-36554D01*
X578396Y-34512D01*
X579706Y-32763D01*
X581234Y-31596D01*
X582981Y-31304D01*
X584727Y-31596D01*
X586256Y-32763D01*
X587566Y-34512D01*
X588440Y-36554D01*
X588876Y-38887D01*
Y-41221D01*
X588440Y-43554D01*
X587566Y-45596D01*
X586256Y-47346D01*
X584727Y-48512D01*
X582981Y-48804D01*
G01X633822Y-31304D02*
X639281Y-48804D01*
X644740Y-31304D01*
G01X661148Y-48804D02*
X652414D01*
Y-31304D01*
X661148D01*
G01X657654Y-39762D02*
X652414D01*
G01X669914Y-48804D02*
Y-31304D01*
X675373D01*
X677119Y-32179D01*
X678211Y-33346D01*
X678648Y-35679D01*
X678211Y-38013D01*
X676901Y-39471D01*
X675373Y-40346D01*
X669914D01*
G01X675373D02*
X678648Y-48804D01*
G01X691781Y-49387D02*
X691344Y-49096D01*
Y-48512D01*
X691781Y-48221D01*
X692218Y-48512D01*
Y-49096D01*
X691781Y-49387D01*
G01X661383Y-79221D02*
X662693Y-77471D01*
X664221Y-76596D01*
X665968Y-76304D01*
X668151Y-76887D01*
X669679Y-78346D01*
X670116Y-80095D01*
X669898Y-81846D01*
X669024Y-83304D01*
X664658Y-86221D01*
X662693Y-88262D01*
X661383Y-91180D01*
X660946Y-93804D01*
X670116D01*
G01X771731Y-76304D02*
Y-93804D01*
G01X766709Y-76304D02*
X776753D01*
G01X783554Y-93804D02*
Y-76304D01*
X789231Y-90887D01*
X794908Y-76304D01*
Y-93804D01*
G01X801272D02*
X806731Y-76304D01*
X812190Y-93804D01*
G01X810224Y-87679D02*
X803237D01*
G01X819646Y-91471D02*
X821393Y-92929D01*
X823358Y-93804D01*
X825104D01*
X826851Y-92929D01*
X828161Y-91471D01*
X828816Y-89429D01*
X828379Y-87388D01*
X827288Y-85637D01*
X825323Y-84471D01*
X822703Y-83887D01*
X821174Y-82721D01*
X820519Y-80679D01*
X820956Y-78637D01*
X822048Y-77179D01*
X823576Y-76304D01*
X825104D01*
X826633Y-76887D01*
X827943Y-78346D01*
G01X836928Y-93804D02*
Y-76304D01*
G01X845224D02*
X836928Y-87096D01*
G01X846534Y-93804D02*
X840639Y-82138D01*
G01X767364Y-31304D02*
Y-48804D01*
X776098D01*
G01X793161D02*
Y-37138D01*
G01Y-39179D02*
X792288Y-38013D01*
X790977Y-37429D01*
X789449Y-37138D01*
X787921Y-37721D01*
X786611Y-38887D01*
X785737Y-40637D01*
X785301Y-42971D01*
X785737Y-45304D01*
X786611Y-47054D01*
X787921Y-48221D01*
X789449Y-48804D01*
X790977Y-48512D01*
X792288Y-47638D01*
X793161Y-46471D01*
G01X802146Y-54054D02*
X803456Y-54637D01*
X805203Y-54054D01*
X806294Y-52888D01*
X807168Y-51429D01*
X808477Y-46763D01*
X811316Y-37138D01*
G01X804329D02*
X808477Y-46763D01*
G01X820956Y-40929D02*
X827943D01*
X827288Y-38887D01*
X826196Y-37721D01*
X824668Y-37138D01*
X823139Y-37429D01*
X821829Y-38304D01*
X820956Y-40346D01*
X820519Y-42096D01*
Y-43846D01*
X820956Y-45596D01*
X822048Y-47346D01*
X823358Y-48512D01*
X824886Y-48804D01*
X826414Y-48221D01*
X827943Y-46471D01*
G01X838674Y-48804D02*
Y-37138D01*
G01Y-39471D02*
X839766Y-38304D01*
X840858Y-37429D01*
X842386Y-37138D01*
X843477Y-37429D01*
X844788Y-38304D01*
G01X931781Y-93804D02*
X930034Y-93512D01*
X928506Y-92346D01*
X927196Y-90596D01*
X926322Y-88554D01*
X925886Y-86221D01*
Y-83887D01*
X926322Y-81554D01*
X927196Y-79512D01*
X928506Y-77763D01*
X930034Y-76596D01*
X931781Y-76304D01*
X933527Y-76596D01*
X935056Y-77763D01*
X936366Y-79512D01*
X937240Y-81554D01*
X937676Y-83887D01*
Y-86221D01*
X937240Y-88554D01*
X936366Y-90596D01*
X935056Y-92346D01*
X933527Y-93512D01*
X931781Y-93804D01*
G01X933527Y-89137D02*
X936148Y-93804D01*
G01X944478Y-76304D02*
Y-88846D01*
X945351Y-91471D01*
X947098Y-93221D01*
X949281Y-93804D01*
X951464Y-93221D01*
X953211Y-91471D01*
X954084Y-88846D01*
Y-76304D01*
G01X964161D02*
X969401D01*
G01X966781D02*
Y-93804D01*
G01X964161D02*
X969401D01*
G01X979259D02*
Y-76304D01*
X989303Y-93804D01*
Y-76304D01*
G01X1006584Y-77763D02*
X1005274Y-76887D01*
X1003746Y-76304D01*
X1001999D01*
X1000034Y-77179D01*
X998506Y-78637D01*
X997414Y-80388D01*
X996541Y-83304D01*
X996322Y-85929D01*
X996759Y-88554D01*
X997414Y-90304D01*
X998724Y-92054D01*
X1000253Y-93221D01*
X1001781Y-93804D01*
X1003309D01*
X1004838Y-93221D01*
X1006148Y-92346D01*
X1007240Y-91180D01*
G01X1019281Y-93804D02*
Y-85929D01*
X1014914Y-76304D01*
G01X1023648D02*
X1019281Y-85929D01*
G01X909478Y-48804D02*
Y-31304D01*
X913844D01*
X915591Y-32179D01*
X916901Y-33346D01*
X917993Y-35095D01*
X918866Y-37138D01*
X919084Y-40054D01*
X918866Y-42971D01*
X917993Y-45013D01*
X916901Y-46763D01*
X915591Y-47929D01*
X913844Y-48804D01*
X909478D01*
G01X928506Y-40929D02*
X935493D01*
X934838Y-38887D01*
X933746Y-37721D01*
X932218Y-37138D01*
X930689Y-37429D01*
X929379Y-38304D01*
X928506Y-40346D01*
X928069Y-42096D01*
Y-43846D01*
X928506Y-45596D01*
X929598Y-47346D01*
X930908Y-48512D01*
X932436Y-48804D01*
X933964Y-48221D01*
X935493Y-46471D01*
G01X946006Y-46763D02*
X947098Y-47929D01*
X948626Y-48804D01*
X949936D01*
X951246Y-48221D01*
X952119Y-47346D01*
X952556Y-46180D01*
X952338Y-44429D01*
X951464Y-43554D01*
X947534Y-41804D01*
X946661Y-39762D01*
X947098Y-38304D01*
X947971Y-37429D01*
X949281Y-37138D01*
X950591Y-37429D01*
X951901Y-38304D01*
G01X966781Y-37138D02*
Y-48804D01*
G01Y-32471D02*
X966344Y-32179D01*
Y-31596D01*
X966781Y-31304D01*
X967218Y-31596D01*
Y-32179D01*
X966781Y-32471D01*
G01X981224Y-53179D02*
X982753Y-54346D01*
X984499Y-54637D01*
X986027Y-54346D01*
X987338Y-52888D01*
X988211Y-50846D01*
Y-37138D01*
G01Y-39471D02*
X987338Y-38304D01*
X986027Y-37429D01*
X984499Y-37138D01*
X982753Y-37721D01*
X981661Y-38887D01*
X980787Y-40929D01*
X980351Y-42971D01*
X980569Y-44721D01*
X981443Y-46763D01*
X982753Y-48221D01*
X984499Y-48804D01*
X985809Y-48512D01*
X987338Y-47346D01*
X988211Y-46180D01*
G01X998069Y-48804D02*
Y-37138D01*
G01Y-40054D02*
X998943Y-38596D01*
X1000253Y-37429D01*
X1001999Y-37138D01*
X1003527Y-37429D01*
X1004838Y-38596D01*
X1005493Y-40637D01*
Y-48804D01*
G01X1016006Y-40929D02*
X1022993D01*
X1022338Y-38887D01*
X1021246Y-37721D01*
X1019718Y-37138D01*
X1018189Y-37429D01*
X1016879Y-38304D01*
X1016006Y-40346D01*
X1015569Y-42096D01*
Y-43846D01*
X1016006Y-45596D01*
X1017098Y-47346D01*
X1018408Y-48512D01*
X1019936Y-48804D01*
X1021464Y-48221D01*
X1022993Y-46471D01*
G01X1033724Y-48804D02*
Y-37138D01*
G01Y-39471D02*
X1034816Y-38304D01*
X1035908Y-37429D01*
X1037436Y-37138D01*
X1038527Y-37429D01*
X1039838Y-38304D01*
G01X1080481Y-76304D02*
X1078734Y-76887D01*
X1077424Y-78346D01*
X1076551Y-80095D01*
X1075896Y-82429D01*
X1075678Y-85054D01*
X1075896Y-87679D01*
X1076551Y-90013D01*
X1077424Y-91763D01*
X1078734Y-93221D01*
X1080481Y-93804D01*
X1082227Y-93221D01*
X1083538Y-91763D01*
X1084411Y-90013D01*
X1085066Y-87679D01*
X1085284Y-85054D01*
X1085066Y-82429D01*
X1084411Y-80095D01*
X1083538Y-78346D01*
X1082227Y-76887D01*
X1080481Y-76304D01*
G01X1097981Y-93804D02*
X1099509Y-93512D01*
X1101256Y-92638D01*
X1102348Y-91180D01*
X1102784Y-89137D01*
X1102348Y-87096D01*
X1101038Y-85346D01*
X1099073Y-84471D01*
X1096889D01*
X1095579Y-83887D01*
X1094487Y-82429D01*
X1094051Y-80388D01*
X1094706Y-78346D01*
X1096234Y-76887D01*
X1097981Y-76304D01*
X1099727Y-76887D01*
X1101256Y-78346D01*
X1101911Y-80388D01*
X1101474Y-82429D01*
X1100383Y-83887D01*
X1099073Y-84471D01*
X1096889D01*
X1094924Y-85346D01*
X1093614Y-87096D01*
X1093178Y-89137D01*
X1093614Y-91180D01*
X1094706Y-92638D01*
X1096453Y-93512D01*
X1097981Y-93804D01*
G01X1111551Y-94387D02*
X1119411Y-76304D01*
G01X1132981D02*
X1131234Y-76887D01*
X1129924Y-78346D01*
X1129051Y-80095D01*
X1128396Y-82429D01*
X1128178Y-85054D01*
X1128396Y-87679D01*
X1129051Y-90013D01*
X1129924Y-91763D01*
X1131234Y-93221D01*
X1132981Y-93804D01*
X1134727Y-93221D01*
X1136038Y-91763D01*
X1136911Y-90013D01*
X1137566Y-87679D01*
X1137784Y-85054D01*
X1137566Y-82429D01*
X1136911Y-80095D01*
X1136038Y-78346D01*
X1134727Y-76887D01*
X1132981Y-76304D01*
G01X1150044Y-93804D02*
X1150481Y-90013D01*
X1151136Y-86804D01*
X1152009Y-83887D01*
X1153101Y-80679D01*
X1154848Y-76304D01*
X1146114D01*
G01X1164051Y-94387D02*
X1171911Y-76304D01*
G01X1181333Y-79221D02*
X1182643Y-77471D01*
X1184171Y-76596D01*
X1185918Y-76304D01*
X1188101Y-76887D01*
X1189629Y-78346D01*
X1190066Y-80095D01*
X1189848Y-81846D01*
X1188974Y-83304D01*
X1184608Y-86221D01*
X1182643Y-88262D01*
X1181333Y-91180D01*
X1180896Y-93804D01*
X1190066D01*
G01X1202981Y-76304D02*
X1201234Y-76887D01*
X1199924Y-78346D01*
X1199051Y-80095D01*
X1198396Y-82429D01*
X1198178Y-85054D01*
X1198396Y-87679D01*
X1199051Y-90013D01*
X1199924Y-91763D01*
X1201234Y-93221D01*
X1202981Y-93804D01*
X1204727Y-93221D01*
X1206038Y-91763D01*
X1206911Y-90013D01*
X1207566Y-87679D01*
X1207784Y-85054D01*
X1207566Y-82429D01*
X1206911Y-80095D01*
X1206038Y-78346D01*
X1204727Y-76887D01*
X1202981Y-76304D01*
G01X1220481Y-93804D02*
Y-76304D01*
X1217861Y-79804D01*
G01Y-93804D02*
X1223101D01*
G01X1237544D02*
X1237981Y-90013D01*
X1238636Y-86804D01*
X1239509Y-83887D01*
X1240601Y-80679D01*
X1242348Y-76304D01*
X1233614D01*
G01X1128178Y-48804D02*
Y-31304D01*
X1132544D01*
X1134291Y-32179D01*
X1135601Y-33346D01*
X1136693Y-35095D01*
X1137566Y-37138D01*
X1137784Y-40054D01*
X1137566Y-42971D01*
X1136693Y-45013D01*
X1135601Y-46763D01*
X1134291Y-47929D01*
X1132544Y-48804D01*
X1128178D01*
G01X1154411D02*
Y-37138D01*
G01Y-39179D02*
X1153538Y-38013D01*
X1152227Y-37429D01*
X1150699Y-37138D01*
X1149171Y-37721D01*
X1147861Y-38887D01*
X1146987Y-40637D01*
X1146551Y-42971D01*
X1146987Y-45304D01*
X1147861Y-47054D01*
X1149171Y-48221D01*
X1150699Y-48804D01*
X1152227Y-48512D01*
X1153538Y-47638D01*
X1154411Y-46471D01*
G01X1167981Y-31304D02*
Y-48804D01*
G01X1164924Y-37138D02*
X1171038D01*
G01X1182206Y-40929D02*
X1189193D01*
X1188538Y-38887D01*
X1187446Y-37721D01*
X1185918Y-37138D01*
X1184389Y-37429D01*
X1183079Y-38304D01*
X1182206Y-40346D01*
X1181769Y-42096D01*
Y-43846D01*
X1182206Y-45596D01*
X1183298Y-47346D01*
X1184608Y-48512D01*
X1186136Y-48804D01*
X1187664Y-48221D01*
X1189193Y-46471D01*
G54D30*
X61284Y643900D03*
X44684Y671800D03*
X208150Y634100D03*
X206900Y630600D03*
X145100Y691600D03*
X143817Y740048D03*
X283400Y531100D03*
X282570Y644150D03*
X272020Y715620D03*
X302070Y612350D03*
X318700Y599000D03*
X284895Y576463D03*
X291204Y688120D03*
X370504Y197291D03*
X358986Y639880D03*
X442535Y34357D03*
X704100Y423800D03*
X787000Y422800D03*
G54D114*
X588647Y32557D03*
G54D12*
X55300Y45000D03*
X33265Y532638D03*
X61454Y639950D03*
X39754Y679750D03*
X95068Y55255D03*
X133277Y613060D03*
X131262Y603311D03*
X134249Y599062D03*
X132295Y617354D03*
X114271Y596454D03*
X106249Y599764D03*
Y607964D03*
Y603864D03*
Y612064D03*
Y624364D03*
Y620264D03*
X109899Y701465D03*
X137649Y687715D03*
X179063Y459780D03*
Y469880D03*
X268000Y470300D03*
Y458200D03*
X268400Y489500D03*
X237863Y539142D03*
X245428Y536660D03*
X215800Y512066D03*
X243238Y528501D03*
X235709Y524700D03*
X235600Y520563D03*
X267700Y605800D03*
X238858Y581690D03*
X240200Y585700D03*
X241142Y572585D03*
X238625Y568522D03*
X253560Y593575D03*
X256882Y642199D03*
X274700Y644572D03*
X265800Y639500D03*
X271990Y723570D03*
X340348Y228017D03*
X347961Y251004D03*
Y247004D03*
X347962Y242193D03*
X344482Y265778D03*
X289600Y551300D03*
X289355Y546706D03*
X347800Y511900D03*
Y500200D03*
X334804Y559544D03*
X334864Y555473D03*
X334795Y563788D03*
X323800Y526000D03*
X302000Y616384D03*
X344300Y581000D03*
X334755Y567922D03*
X334799Y572721D03*
X332553Y576849D03*
X321475Y678443D03*
X291318Y684153D03*
X334723Y677472D03*
X320083Y674407D03*
X389536Y585080D03*
X389200Y637900D03*
X389500Y589100D03*
X389236Y628580D03*
X389600Y605400D03*
X387836Y617980D03*
X389500Y593200D03*
X389600Y601300D03*
X388195Y568431D03*
X388244Y572999D03*
X386102Y694223D03*
X385400Y683900D03*
X385300Y679800D03*
Y675600D03*
X434185Y38057D03*
X442585Y21957D03*
X435858Y56153D03*
X442685Y30457D03*
Y26157D03*
X442616Y38147D03*
X489800Y30000D03*
X489700Y21800D03*
X489800Y26000D03*
X527600Y54648D03*
X527597Y50148D03*
X618596Y55138D03*
X581904Y41467D03*
X579347Y37207D03*
X650383Y525811D03*
X733800Y431000D03*
X851222Y149514D03*
X846611Y169478D03*
X848968Y203864D03*
Y215964D03*
X836239Y356008D03*
X836213Y360311D03*
X836216Y351914D03*
X816700Y430000D03*
X863630Y215262D03*
G54D21*
X34652Y111485D03*
X33297Y703990D03*
X148206Y21054D03*
X261147Y405580D03*
X486498Y356293D03*
X807831Y734367D03*
X899219Y47960D03*
G54D105*
X488838Y164744D03*
G54D123*
X745669Y510236D03*
X844094D03*
G54D31*
X65714Y665850D03*
X306300Y638600D03*
X295634Y710070D03*
G54D115*
X646021Y42707D03*
X630273D03*
G54D22*
X70865Y98425D03*
Y472441D03*
X49212Y740157D03*
X314960Y472441D03*
X364173Y740157D03*
X405511Y39370D03*
X587795Y307087D03*
X590551Y472441D03*
X612204Y606299D03*
X875984Y31496D03*
Y472441D03*
Y606299D03*
Y740157D03*
G54D106*
X530998Y64511D03*
Y78351D03*
G54D40*
X123586Y460300D03*
Y465300D03*
Y470300D03*
Y475300D03*
Y480300D03*
Y485300D03*
Y490300D03*
Y495300D03*
X162144Y490300D03*
Y485300D03*
Y480300D03*
Y475300D03*
Y470300D03*
Y465300D03*
Y460300D03*
Y495300D03*
X220521Y460300D03*
Y465300D03*
Y470300D03*
Y475300D03*
Y480300D03*
Y485300D03*
Y490300D03*
X259079D03*
Y485300D03*
Y480300D03*
Y475300D03*
Y470300D03*
Y465300D03*
Y460300D03*
X220521Y495300D03*
X259079D03*
G54D13*
X58700Y45000D03*
X36665Y532638D03*
X64854Y639950D03*
X43154Y679750D03*
X98468Y55255D03*
X136677Y613060D03*
X134662Y603311D03*
X137649Y599062D03*
X135695Y617354D03*
X117671Y596454D03*
X109649Y599764D03*
Y607964D03*
Y603864D03*
Y612064D03*
Y624364D03*
Y620264D03*
X113299Y701465D03*
X141049Y687715D03*
X182463Y459780D03*
Y469880D03*
X271400Y470300D03*
Y458200D03*
X271800Y489500D03*
X241263Y539142D03*
X248828Y536660D03*
X219200Y512066D03*
X246638Y528501D03*
X239109Y524700D03*
X239000Y520563D03*
X271100Y605800D03*
X242258Y581690D03*
X243600Y585700D03*
X244542Y572585D03*
X242025Y568522D03*
X256960Y593575D03*
X260282Y642199D03*
X278100Y644572D03*
X269200Y639500D03*
X275390Y723570D03*
X343748Y228017D03*
X351361Y251004D03*
Y247004D03*
X351362Y242193D03*
X347882Y265778D03*
X293000Y551300D03*
X292755Y546706D03*
X351200Y511900D03*
Y500200D03*
X338204Y559544D03*
X338264Y555473D03*
X338195Y563788D03*
X327200Y526000D03*
X305400Y616384D03*
X347700Y581000D03*
X338155Y567922D03*
X338199Y572721D03*
X335953Y576849D03*
X324875Y678443D03*
X294718Y684153D03*
X338123Y677472D03*
X323483Y674407D03*
X392936Y585080D03*
X392600Y637900D03*
X392900Y589100D03*
X392636Y628580D03*
X393000Y605400D03*
X391236Y617980D03*
X392900Y593200D03*
X393000Y601300D03*
X391595Y568431D03*
X391644Y572999D03*
X389502Y694223D03*
X388800Y683900D03*
X388700Y679800D03*
Y675600D03*
X437585Y38057D03*
X445985Y21957D03*
X439258Y56153D03*
X446085Y30457D03*
Y26157D03*
X446016Y38147D03*
X493200Y30000D03*
X493100Y21800D03*
X493200Y26000D03*
X531000Y54648D03*
X530997Y50148D03*
X621996Y55138D03*
X585304Y41467D03*
X582747Y37207D03*
X653783Y525811D03*
X737200Y431000D03*
X854622Y149514D03*
X850011Y169478D03*
X852368Y203864D03*
Y215964D03*
X839639Y356008D03*
X839613Y360311D03*
X839616Y351914D03*
X820100Y430000D03*
X867030Y215262D03*
G54D124*
X801024Y24409D03*
X811024D03*
X821024D03*
G54D125*
X869622Y191265D03*
X866114Y383399D03*
G54D14*
X34000Y54300D03*
X73768Y64555D03*
X93614Y507152D03*
X73427Y695585D03*
X127300Y643300D03*
X115619Y712795D03*
X283032Y736236D03*
X345034Y128412D03*
X294018Y665582D03*
X352180Y642014D03*
X539108Y74841D03*
X577404Y60567D03*
X641347Y63007D03*
X598947Y69007D03*
X603747Y67707D03*
X832572Y177477D03*
G54D23*
X44206Y543876D03*
X36758Y543881D03*
X44187Y555153D03*
X36687D03*
X44000Y549500D03*
X36500D03*
X44206Y538249D03*
X36658Y538254D03*
X44106Y532622D03*
X64746Y647850D03*
X130400Y534600D03*
X140300Y529700D03*
X130400Y530300D03*
X140467Y537795D03*
X121803Y613818D03*
X126700Y599000D03*
X182439Y474031D03*
X212100Y495300D03*
X149692Y519686D03*
Y515686D03*
X203300Y503300D03*
X191528Y643963D03*
X148549Y683715D03*
X158549Y711215D03*
X271400Y474380D03*
X284445Y561694D03*
X251396Y557061D03*
X251477Y563068D03*
X267400Y553100D03*
X275825Y541121D03*
X242996Y560398D03*
Y564498D03*
X243300Y601000D03*
X243700Y589800D03*
X236100Y634300D03*
X252100Y578300D03*
X251100Y585700D03*
X252000Y573500D03*
X254125Y567260D03*
X272119Y574462D03*
X262976Y669731D03*
X238889Y662667D03*
X275420Y719420D03*
X351182Y193578D03*
X351482Y178678D03*
Y257778D03*
X343718Y232181D03*
X348500Y543800D03*
X351261Y507831D03*
X286900Y527300D03*
X287000Y522800D03*
Y535000D03*
X306453Y620550D03*
X299715Y592831D03*
X314644Y582263D03*
X348066Y594759D03*
X344200Y585500D03*
X294782Y691947D03*
X286070Y647978D03*
Y652044D03*
X345600Y672000D03*
X370680Y245508D03*
X365881Y225861D03*
X370680Y241308D03*
X367661Y475491D03*
X363002Y480368D03*
X389200Y533400D03*
X389800Y564400D03*
X366064Y635920D03*
X391200Y613900D03*
X393000Y597200D03*
X392581Y622265D03*
X493200Y42000D03*
X493600Y34000D03*
X482926Y59562D03*
X489214Y51841D03*
X589420Y50435D03*
X653746Y521683D03*
X653783Y530195D03*
X657078Y517560D03*
X737200Y426800D03*
X850011Y165178D03*
X852368Y207864D03*
Y211864D03*
X849456Y344740D03*
X848860Y403998D03*
Y395998D03*
Y399998D03*
X820100Y425800D03*
G54D50*
X119400Y642500D03*
X123100D03*
X207900Y641500D03*
X228200Y642700D03*
X215406Y641492D03*
X282600Y685700D03*
X258000Y657300D03*
X297767Y585918D03*
X294167D03*
X336631Y685326D03*
X370650Y193614D03*
X364600Y495500D03*
X849625Y181277D03*
X842984Y374569D03*
X893974Y182735D03*
X890639Y371160D03*
X878439Y404523D03*
G54D107*
X536993Y54351D03*
Y47945D03*
G54D32*
X68273Y656107D03*
X65714D03*
X63155D03*
X60596D03*
Y675593D03*
X63155D03*
X65714D03*
X68273D03*
X70832Y656107D03*
Y675593D03*
X311418Y628857D03*
X308859D03*
X306300D03*
X303741D03*
X301182D03*
X300752Y700327D03*
X298193D03*
X295634D03*
X293075D03*
X290516D03*
X301182Y648343D03*
X303741D03*
X306300D03*
X308859D03*
X311418D03*
X290516Y719813D03*
X293075D03*
X295634D03*
X298193D03*
X300752D03*
G54D41*
X119300Y518400D03*
X136000Y628900D03*
X81784Y671500D03*
X85400Y638516D03*
X188500Y693600D03*
X171747Y708475D03*
X258823Y628146D03*
X263000Y679300D03*
X243731Y705874D03*
X218623Y655646D03*
X225400Y716600D03*
X317600Y610400D03*
X322000Y645600D03*
X314720Y681820D03*
X311704Y715720D03*
X369400Y119500D03*
X523301Y54449D03*
X622537Y34526D03*
X589104Y43267D03*
X586647Y60807D03*
X669447Y37707D03*
X845625Y181177D03*
X838972Y374569D03*
G54D116*
X673647Y35657D03*
Y36157D03*
X904262Y71265D03*
Y71765D03*
G54D24*
X40806Y543876D03*
X33358Y543881D03*
X40787Y555153D03*
X33287D03*
X40600Y549500D03*
X33100D03*
X40806Y538249D03*
X33258Y538254D03*
X40706Y532622D03*
X61346Y647850D03*
X127000Y534600D03*
X136900Y529700D03*
X127000Y530300D03*
X137067Y537795D03*
X118403Y613818D03*
X123300Y599000D03*
X179039Y474031D03*
X208700Y495300D03*
X146292Y519686D03*
Y515686D03*
X199900Y503300D03*
X188128Y643963D03*
X145149Y683715D03*
X155149Y711215D03*
X268000Y474380D03*
X281045Y561694D03*
X247996Y557061D03*
X248077Y563068D03*
X264000Y553100D03*
X272425Y541121D03*
X239596Y560398D03*
Y564498D03*
X283500Y527300D03*
X283600Y522800D03*
Y535000D03*
X239900Y601000D03*
X240300Y589800D03*
X232700Y634300D03*
X248700Y578300D03*
X247700Y585700D03*
X248600Y573500D03*
X250725Y567260D03*
X268719Y574462D03*
X259576Y669731D03*
X282670Y647978D03*
X235489Y662667D03*
X282670Y652044D03*
X272020Y719420D03*
X347782Y193578D03*
X348082Y178678D03*
Y257778D03*
X340318Y232181D03*
X345100Y543800D03*
X347861Y507831D03*
X303053Y620550D03*
X296315Y592831D03*
X311244Y582263D03*
X344666Y594759D03*
X340800Y585500D03*
X291382Y691947D03*
X342200Y672000D03*
X367280Y245508D03*
X362481Y225861D03*
X367280Y241308D03*
X364261Y475491D03*
X359602Y480368D03*
X385800Y533400D03*
X386400Y564400D03*
X362664Y635920D03*
X387800Y613900D03*
X389600Y597200D03*
X389181Y622265D03*
X489800Y42000D03*
X490200Y34000D03*
X479526Y59562D03*
X485814Y51841D03*
X586020Y50435D03*
X650346Y521683D03*
X650383Y530195D03*
X653678Y517560D03*
X733800Y426800D03*
X846611Y165178D03*
X848968Y207864D03*
Y211864D03*
X846056Y344740D03*
X845460Y403998D03*
Y395998D03*
Y399998D03*
X816700Y425800D03*
G54D51*
X135019Y714845D03*
G54D126*
X849018Y192564D03*
G54D60*
X211732Y670886D03*
X207795D03*
X203858D03*
X209764Y688956D03*
X205827D03*
X223544Y670886D03*
X219607D03*
X215670D03*
X221575Y688956D03*
X217638D03*
X213701D03*
G54D108*
X544495Y54351D03*
Y47945D03*
G54D117*
X706299Y83661D03*
Y201771D03*
X804724Y83661D03*
Y201772D03*
G54D33*
X55971Y660732D03*
Y663291D03*
Y665850D03*
Y668409D03*
Y670968D03*
X75457D03*
Y668409D03*
Y665850D03*
Y663291D03*
Y660732D03*
X296557Y633482D03*
Y636041D03*
X316043D03*
Y633482D03*
X285891Y704952D03*
Y707511D03*
X305377D03*
Y704952D03*
X296557Y638600D03*
Y641159D03*
Y643718D03*
X316043D03*
Y641159D03*
Y638600D03*
X285891Y710070D03*
Y712629D03*
Y715188D03*
X305377D03*
Y712629D03*
Y710070D03*
G54D42*
X119300Y514800D03*
X136000Y625300D03*
X85400Y634916D03*
X81784Y667900D03*
X188500Y690000D03*
X171747Y704875D03*
X258823Y624546D03*
X263000Y675700D03*
X243731Y702274D03*
X218623Y652046D03*
X225400Y713000D03*
X317600Y606800D03*
X322000Y642000D03*
X314720Y678220D03*
X311704Y712120D03*
X369400Y115900D03*
X523301Y50849D03*
X622537Y30926D03*
X589104Y39667D03*
X586647Y57207D03*
X669447Y34107D03*
X845625Y177577D03*
X838972Y370969D03*
G54D15*
X34000Y48700D03*
X73768Y58955D03*
X93614Y501552D03*
X127300Y637700D03*
X73427Y689985D03*
X115619Y707195D03*
X283032Y730636D03*
X345034Y122812D03*
X352180Y636414D03*
X294018Y659982D03*
X539108Y69241D03*
X577404Y54967D03*
X598947Y63407D03*
X641347Y57407D03*
X603747Y62107D03*
X832572Y171877D03*
G54D70*
X267100Y671900D03*
Y668300D03*
X303100Y661630D03*
Y658030D03*
G54D61*
X163189Y669291D03*
G54D43*
X135012Y521048D03*
X125788D03*
X135012Y514552D03*
X125788D03*
X270521Y612019D03*
X279745D03*
X270521Y618515D03*
X279745D03*
G54D109*
X531093Y39133D03*
Y34133D03*
Y29133D03*
Y24133D03*
G54D118*
X714454Y422965D03*
Y406785D03*
X717014Y422965D03*
X719574D03*
X722134D03*
Y406785D03*
X719574D03*
X717014D03*
X797354Y421965D03*
X799914D03*
X802474D03*
X805034D03*
Y405785D03*
X802474D03*
X799914D03*
X797354D03*
G54D52*
X125376Y705002D03*
Y706971D03*
Y708939D03*
Y710908D03*
Y712876D03*
Y714845D03*
Y716814D03*
Y718782D03*
Y720751D03*
Y722719D03*
Y724688D03*
X144662Y708939D03*
Y706971D03*
Y705002D03*
Y724688D03*
Y722719D03*
Y720751D03*
Y718782D03*
Y716814D03*
Y714845D03*
Y712876D03*
Y710908D03*
G54D127*
X851518Y192564D03*
G54D16*
X61024Y34449D03*
X33464D03*
X56102Y24606D03*
X38386D03*
X108268Y44292D03*
X80708D03*
X103346Y34449D03*
X85630D03*
G54D25*
X66278Y540794D03*
Y543943D03*
Y537644D03*
Y547093D03*
Y550242D03*
Y553392D03*
Y556542D03*
Y559691D03*
Y562841D03*
Y565990D03*
Y578589D03*
Y581738D03*
Y584888D03*
Y569140D03*
Y572290D03*
Y575439D03*
X85175Y547093D03*
X91474Y540794D03*
X88325D03*
X85175D03*
X91474Y543943D03*
X88325D03*
X85175D03*
X91474Y537644D03*
X88325D03*
X85175D03*
X72577Y540794D03*
X69427D03*
X72577Y543943D03*
X69427D03*
X72577Y537644D03*
X69427D03*
X91474Y547093D03*
X88325D03*
X72577D03*
X69427D03*
X91474Y550242D03*
X88325D03*
X85175D03*
X72577D03*
X69427D03*
X91474Y553392D03*
X88325D03*
X85175D03*
X72577D03*
X69427D03*
X91474Y556542D03*
X88325D03*
X85175D03*
X72577D03*
X69427D03*
X91474Y559691D03*
X88325D03*
X85175D03*
X72577D03*
X69427D03*
X91474Y562841D03*
X88325D03*
X85175D03*
X72577D03*
X69427D03*
X91474Y565990D03*
X88325D03*
X85175D03*
X72577D03*
X69427D03*
X91474Y569140D03*
Y572290D03*
Y575439D03*
Y578589D03*
Y581738D03*
Y584888D03*
X88325Y578589D03*
X85175D03*
X88325Y581738D03*
X85175D03*
X88325Y584888D03*
X85175D03*
X72577Y578589D03*
X69427D03*
X72577Y581738D03*
X69427D03*
X72577Y584888D03*
X69427D03*
X88325Y569140D03*
X85175D03*
X72577D03*
X69427D03*
X88325Y572290D03*
X85175D03*
X72577D03*
X69427D03*
X88325Y575439D03*
X85175D03*
X72577D03*
X69427D03*
X138970Y632277D03*
X128700Y615500D03*
X138700Y636655D03*
X113672Y605134D03*
X113512Y613401D03*
X113426Y609234D03*
X108137Y615870D03*
X113400Y621400D03*
X133835Y609620D03*
X179100Y455800D03*
X194411Y485447D03*
X193400Y463300D03*
X154724Y547244D03*
Y550394D03*
Y553543D03*
Y556693D03*
Y559842D03*
Y562992D03*
X157874Y547244D03*
Y550394D03*
Y553543D03*
Y556693D03*
Y559842D03*
Y562992D03*
X161023Y547244D03*
Y550394D03*
Y553543D03*
Y556693D03*
Y559842D03*
Y562992D03*
X164173Y537795D03*
Y540945D03*
Y544094D03*
Y547244D03*
Y550394D03*
Y553543D03*
Y556693D03*
Y559842D03*
Y562992D03*
X167323Y537795D03*
Y540945D03*
Y544094D03*
Y547244D03*
Y550394D03*
Y553543D03*
Y556693D03*
Y559842D03*
Y562992D03*
X170472Y537795D03*
Y540945D03*
Y544094D03*
Y547244D03*
Y550394D03*
Y553543D03*
Y556693D03*
Y559842D03*
Y562992D03*
X173622Y537795D03*
Y540945D03*
Y544094D03*
Y547244D03*
Y550394D03*
Y553543D03*
Y556693D03*
Y559842D03*
Y562992D03*
X176771Y537795D03*
Y540945D03*
Y544094D03*
Y547244D03*
Y550394D03*
Y553543D03*
Y556693D03*
X179921Y537795D03*
Y540945D03*
Y544094D03*
Y547244D03*
Y550394D03*
Y553543D03*
Y556693D03*
Y562992D03*
X183071Y537795D03*
Y540945D03*
Y544094D03*
Y547244D03*
Y550394D03*
Y553543D03*
Y556693D03*
Y562992D03*
X186220Y537795D03*
Y540945D03*
Y544094D03*
Y547244D03*
Y550394D03*
Y553543D03*
Y556693D03*
Y562992D03*
X189370Y537795D03*
Y540945D03*
Y544094D03*
Y547244D03*
Y550394D03*
Y553543D03*
Y556693D03*
Y562992D03*
X192519Y537795D03*
Y540945D03*
Y544094D03*
Y547244D03*
Y550394D03*
Y553543D03*
Y556693D03*
Y562992D03*
X195669Y537795D03*
Y540945D03*
Y544094D03*
Y547244D03*
Y550394D03*
Y553543D03*
Y556693D03*
Y562992D03*
X198819Y537795D03*
Y540945D03*
Y544094D03*
Y547244D03*
Y550394D03*
Y553543D03*
Y556693D03*
X201968Y537795D03*
Y540945D03*
Y544094D03*
Y547244D03*
Y550394D03*
Y553543D03*
Y556693D03*
Y559842D03*
Y562992D03*
X205118Y537795D03*
Y540945D03*
Y544094D03*
Y547244D03*
Y550394D03*
Y553543D03*
Y556693D03*
Y559842D03*
Y562992D03*
X208267Y537795D03*
Y540945D03*
Y544094D03*
Y547244D03*
Y550394D03*
Y553543D03*
Y556693D03*
Y559842D03*
Y562992D03*
X211417Y537795D03*
Y540945D03*
Y544094D03*
Y547244D03*
Y550394D03*
Y553543D03*
Y556693D03*
Y559842D03*
Y562992D03*
X167680Y510640D03*
X183750Y524200D03*
X176900Y496500D03*
X190929Y512592D03*
X154724Y566142D03*
Y569291D03*
Y572441D03*
Y575590D03*
Y578740D03*
Y581890D03*
Y585039D03*
Y588189D03*
Y591338D03*
Y594488D03*
X157874Y566142D03*
Y569291D03*
Y572441D03*
Y575590D03*
Y578740D03*
Y581890D03*
Y585039D03*
Y588189D03*
Y591338D03*
Y594488D03*
X161023Y566142D03*
Y569291D03*
Y572441D03*
Y575590D03*
Y578740D03*
Y581890D03*
Y585039D03*
Y588189D03*
Y591338D03*
Y594488D03*
X164173Y566142D03*
Y569291D03*
Y572441D03*
Y575590D03*
Y578740D03*
Y581890D03*
Y585039D03*
Y588189D03*
Y591338D03*
Y594488D03*
Y597638D03*
Y600787D03*
Y603937D03*
X167323Y566142D03*
Y569291D03*
Y572441D03*
Y575590D03*
Y578740D03*
Y581890D03*
Y585039D03*
Y588189D03*
Y591338D03*
Y594488D03*
Y597638D03*
Y600787D03*
Y603937D03*
X170472Y566142D03*
Y569291D03*
Y572441D03*
Y575590D03*
Y578740D03*
Y581890D03*
Y585039D03*
Y588189D03*
Y591338D03*
Y594488D03*
Y597638D03*
Y600787D03*
Y603937D03*
X173622Y566142D03*
Y569291D03*
Y572441D03*
Y575590D03*
Y578740D03*
Y581890D03*
Y585039D03*
Y588189D03*
Y591338D03*
Y594488D03*
Y597638D03*
Y600787D03*
Y603937D03*
X176771Y585039D03*
Y588189D03*
Y591338D03*
Y594488D03*
Y597638D03*
Y600787D03*
Y603937D03*
X179921Y566142D03*
Y569291D03*
Y572441D03*
Y575590D03*
Y578740D03*
Y585039D03*
Y588189D03*
Y591338D03*
Y594488D03*
Y597638D03*
Y600787D03*
Y603937D03*
X183071Y566142D03*
Y569291D03*
Y572441D03*
Y575590D03*
Y578740D03*
Y585039D03*
Y588189D03*
Y591338D03*
Y594488D03*
Y597638D03*
Y600787D03*
Y603937D03*
X186220Y566142D03*
Y569291D03*
Y572441D03*
Y575590D03*
Y578740D03*
Y585039D03*
Y588189D03*
Y591338D03*
Y594488D03*
Y597638D03*
Y600787D03*
Y603937D03*
X189370Y566142D03*
Y569291D03*
Y572441D03*
Y575590D03*
Y578740D03*
Y585039D03*
Y588189D03*
Y591338D03*
Y594488D03*
Y597638D03*
Y600787D03*
Y603937D03*
X192519Y566142D03*
Y569291D03*
Y572441D03*
Y575590D03*
Y578740D03*
Y585039D03*
Y588189D03*
Y591338D03*
Y594488D03*
Y597638D03*
Y600787D03*
Y603937D03*
X195669Y566142D03*
Y569291D03*
Y572441D03*
Y575590D03*
Y578740D03*
Y585039D03*
Y588189D03*
Y591338D03*
Y594488D03*
Y597638D03*
Y600787D03*
Y603937D03*
X198819Y585039D03*
Y588189D03*
Y591338D03*
Y594488D03*
Y597638D03*
Y600787D03*
Y603937D03*
X201968Y566142D03*
Y569291D03*
Y572441D03*
Y575590D03*
Y578740D03*
Y581890D03*
Y585039D03*
Y588189D03*
Y591338D03*
Y594488D03*
Y597638D03*
Y600787D03*
Y603937D03*
X205118Y566142D03*
Y569291D03*
Y572441D03*
Y575590D03*
Y578740D03*
Y581890D03*
Y585039D03*
Y588189D03*
Y591338D03*
Y594488D03*
Y597638D03*
Y600787D03*
Y603937D03*
X208267Y566142D03*
Y569291D03*
Y572441D03*
Y575590D03*
Y578740D03*
Y581890D03*
Y585039D03*
Y588189D03*
Y591338D03*
Y594488D03*
Y597638D03*
Y600787D03*
Y603937D03*
X211417Y566142D03*
Y569291D03*
Y572441D03*
Y575590D03*
Y578740D03*
Y581890D03*
Y585039D03*
Y588189D03*
Y591338D03*
Y594488D03*
Y597638D03*
Y600787D03*
Y603937D03*
X197611Y630698D03*
X193400Y630600D03*
X148210Y629830D03*
X150849Y710215D03*
X240900Y440900D03*
X236400Y440800D03*
X214567Y547244D03*
Y550394D03*
Y553543D03*
Y556693D03*
Y559842D03*
Y562992D03*
X217716Y547244D03*
Y550394D03*
Y553543D03*
Y556693D03*
Y559842D03*
Y562992D03*
X220866Y547244D03*
Y550394D03*
Y553543D03*
Y556693D03*
Y559842D03*
Y562992D03*
X214567Y566142D03*
Y569291D03*
Y572441D03*
Y575590D03*
Y578740D03*
Y581890D03*
Y585039D03*
Y588189D03*
Y591338D03*
Y594488D03*
X217716Y566142D03*
Y569291D03*
Y572441D03*
Y575590D03*
Y578740D03*
Y581890D03*
Y585039D03*
Y588189D03*
Y591338D03*
Y594488D03*
X220866Y566142D03*
Y569291D03*
Y572441D03*
Y575590D03*
Y578740D03*
Y581890D03*
Y585039D03*
Y588189D03*
Y591338D03*
Y594488D03*
X277600Y680200D03*
X293326Y494174D03*
X288000Y561000D03*
X336881Y530496D03*
X336953Y534506D03*
X387500Y458200D03*
X378200Y476600D03*
X390769Y495379D03*
X384500Y616500D03*
X383313Y621780D03*
X366500Y586300D03*
X395127Y568056D03*
X395100Y572899D03*
X364600Y670800D03*
X479040Y47134D03*
X531050Y46998D03*
X864992Y175435D03*
X861420Y367269D03*
G54D34*
X60600Y670900D03*
X65900Y671000D03*
X65714Y665850D03*
X60800Y660900D03*
X60700Y665900D03*
X65700Y660900D03*
X139916Y709422D03*
X130019Y709695D03*
X139916Y705822D03*
X130019Y706095D03*
X135019D03*
X70700Y671000D03*
X70800Y660700D03*
X70600Y665800D03*
X139916Y713022D03*
Y716622D03*
Y720222D03*
Y723822D03*
X130019Y713295D03*
Y716895D03*
Y720495D03*
X135019Y710595D03*
Y723595D03*
Y719095D03*
Y714845D03*
X130019Y724095D03*
X311386Y633450D03*
X306300Y638600D03*
X301286Y638650D03*
X301386Y633650D03*
X306286D03*
X311186Y638550D03*
X300720Y704920D03*
X300520Y710020D03*
X290620Y710120D03*
X295634Y710070D03*
X290720Y705120D03*
X295620D03*
X301186Y643650D03*
X306486Y643750D03*
X311286D03*
X300620Y715220D03*
X290520Y715120D03*
X295820Y715220D03*
X365164Y612620D03*
X358864D03*
X371400Y606400D03*
X358800Y606300D03*
X365300Y606500D03*
X371400Y612700D03*
X371300Y618800D03*
X365500Y619000D03*
X358900Y618800D03*
X468000Y31500D03*
Y39500D03*
X464000Y35500D03*
X468000Y35400D03*
X472000Y35500D03*
X603943Y42806D03*
X608143Y42906D03*
X603943Y47006D03*
X608043D03*
X857020Y383172D03*
Y379572D03*
Y386772D03*
X875272Y186265D03*
X878872D03*
X860872D03*
X871672D03*
X868072D03*
X864472D03*
X878372Y191265D03*
X878872Y196265D03*
X864472D03*
X868072D03*
X871672D03*
X875272D03*
X865372Y191265D03*
X873872D03*
X869622D03*
X860872Y196265D03*
Y191265D03*
X871420Y383172D03*
X875020D03*
Y379572D03*
X871420D03*
X867820D03*
X860620D03*
X864220D03*
X875020Y386772D03*
X871420D03*
X867820D03*
X860620D03*
X864220D03*
X867820Y383172D03*
X860620D03*
X864220D03*
G54D62*
X197920Y712091D03*
Y736891D03*
X367700Y136500D03*
Y161300D03*
G54D71*
X275956Y653733D03*
X268456Y649858D03*
Y657608D03*
X346850Y662500D03*
X339350Y666375D03*
Y658625D03*
X496678Y61151D03*
X489178Y57276D03*
Y65026D03*
X710550Y30775D03*
Y23025D03*
X718050Y26900D03*
G54D44*
X125600Y630800D03*
Y623200D03*
X79050Y637546D03*
Y629946D03*
X133600Y637700D03*
X91550Y654554D03*
Y662154D03*
X83750Y654654D03*
Y662254D03*
X133600Y645300D03*
X117149Y730715D03*
Y738315D03*
X109449Y730715D03*
Y738315D03*
X124820Y732391D03*
Y739991D03*
X94020Y730691D03*
Y738291D03*
X101749Y730715D03*
Y738315D03*
X132651Y732415D03*
Y740015D03*
X211800Y710100D03*
Y717700D03*
X219600Y710100D03*
Y717700D03*
X333500Y111200D03*
Y118800D03*
X332436Y627504D03*
Y635104D03*
X324636Y627604D03*
Y635204D03*
X311936Y609096D03*
Y601496D03*
X309236Y658404D03*
Y666004D03*
X317136Y658404D03*
Y666004D03*
X313870Y699174D03*
Y706774D03*
X321670Y699074D03*
Y706674D03*
X309100Y682800D03*
Y675200D03*
X306370Y731174D03*
Y738774D03*
X298470Y731174D03*
Y738774D03*
X663847Y39907D03*
Y32307D03*
X655847Y39907D03*
Y32307D03*
X898622Y76514D03*
Y68914D03*
X890622Y76514D03*
Y68914D03*
X882622Y76514D03*
Y68914D03*
X899491Y398439D03*
Y406039D03*
X891794Y398441D03*
Y406041D03*
X884102Y398456D03*
Y406056D03*
X899597Y384357D03*
Y391957D03*
G54D35*
X89764Y238386D03*
X309252Y413583D03*
G54D128*
X856271Y393042D03*
X858240D03*
Y373756D03*
X856271D03*
X859779Y200908D03*
X861748D03*
X863716D03*
X865685D03*
X867653D03*
X869622D03*
X871591D03*
X873559D03*
X875528D03*
X877496D03*
X879465D03*
Y181622D03*
X877496D03*
X875528D03*
X873559D03*
X871591D03*
X869622D03*
X867653D03*
X865685D03*
X863716D03*
X861748D03*
X859779D03*
X860208Y393042D03*
X862177D03*
X864145D03*
X866114D03*
X868083D03*
X870051D03*
X872020D03*
X873988D03*
X875957D03*
Y373756D03*
X873988D03*
X872020D03*
X870051D03*
X868083D03*
X866114D03*
X864145D03*
X862177D03*
X860208D03*
G54D17*
X43000Y48500D03*
Y54500D03*
X82768Y58755D03*
Y64755D03*
X277600Y674600D03*
Y665600D03*
G54D53*
X134700Y694850D03*
G54D80*
X305906Y182874D03*
G54D26*
X56844Y588651D03*
X28971Y675883D03*
X43800Y675800D03*
X55895Y643491D03*
X49500Y659909D03*
X130500Y599000D03*
X128800Y611100D03*
X140800Y616400D03*
X88266Y621165D03*
X127263Y594662D03*
X138473Y603273D03*
X128800Y694400D03*
X118477Y702077D03*
X122100Y698500D03*
X112850Y641488D03*
X112403Y656627D03*
X77903Y689785D03*
X73265Y647355D03*
X83450Y646620D03*
X139000Y740015D03*
X104132Y722843D03*
X199000Y479500D03*
X196100Y524600D03*
X200300Y525500D03*
X188158Y527500D03*
X192800Y529100D03*
X179021Y528902D03*
X173175Y528444D03*
X169420Y526499D03*
X183350Y527900D03*
X165572Y529088D03*
X154151Y523478D03*
X160743Y527786D03*
X153985Y527761D03*
X144800Y549100D03*
X204979Y525545D03*
X213050Y525000D03*
X204843Y623300D03*
X200000Y618900D03*
X212750Y618700D03*
X191435Y614794D03*
X187221Y617507D03*
X182819Y617616D03*
X176993Y613763D03*
X175300Y618200D03*
X172048Y614508D03*
X161958Y633782D03*
X143221Y611975D03*
X149800Y618700D03*
X147262Y615302D03*
X144993Y626564D03*
X142500Y599062D03*
X155378Y618114D03*
X210800Y622500D03*
X157450Y626650D03*
X193000Y648700D03*
X160200Y699165D03*
X143100Y696800D03*
X144048Y735514D03*
X276995Y558100D03*
X230838Y566081D03*
X235484Y561538D03*
X260513Y564135D03*
X266700Y548600D03*
X250901Y531106D03*
X258969Y537520D03*
X221014Y526000D03*
X237344Y513444D03*
X233900Y516000D03*
X271966Y565966D03*
X266325Y557905D03*
X228541Y529541D03*
X243950Y522900D03*
X231800Y538900D03*
X229762Y522829D03*
X219800Y517100D03*
X242449Y532550D03*
X254560Y548551D03*
X253202Y544298D03*
X223593Y634091D03*
X234797Y568900D03*
X236421Y574788D03*
X235310Y585700D03*
X234034Y578517D03*
X246433Y567987D03*
X260131Y574893D03*
X217600Y620700D03*
X226300Y618800D03*
X237800Y629800D03*
X250087Y591300D03*
X236056Y596885D03*
X238700Y617900D03*
X255935Y583784D03*
X242866Y577122D03*
X261455Y579009D03*
X239963Y613061D03*
X260500Y637500D03*
X261025Y593260D03*
X239000Y687300D03*
X257000Y698900D03*
X281602Y657563D03*
X258400Y662000D03*
X279920Y703460D03*
X252400Y705750D03*
X262335Y653750D03*
X239842Y681600D03*
X252700Y643400D03*
X270100Y662700D03*
X222306Y737851D03*
X221987Y728528D03*
X279900Y715400D03*
X261305Y715957D03*
X339900Y123700D03*
X343292Y187765D03*
X338955Y179994D03*
X342228Y247493D03*
X341105Y237114D03*
X340000Y262678D03*
X343582Y271028D03*
X339387Y241609D03*
X350900Y485348D03*
X353700Y480668D03*
X350300Y443500D03*
X356502Y474400D03*
X338963Y440163D03*
X347800Y440100D03*
X288100Y542900D03*
X288883Y555249D03*
X349600Y539100D03*
X345864Y531341D03*
X351500Y524125D03*
X313791Y550221D03*
X330100Y559544D03*
X309592Y550099D03*
X327900Y555900D03*
X330188Y563900D03*
X322800Y549300D03*
X320700Y543250D03*
X336800Y545700D03*
X349422Y553098D03*
X348597Y548003D03*
X336800Y510000D03*
X297999Y550096D03*
X322000Y520700D03*
X341596Y500750D03*
X290889Y530299D03*
X316000Y530000D03*
X290889Y525299D03*
Y535299D03*
X316000Y536000D03*
X351300Y504000D03*
X298613Y597750D03*
X347451Y576772D03*
X349373Y571300D03*
X346577Y567339D03*
X327874Y576249D03*
X342300Y571800D03*
X328200D03*
X330200Y568100D03*
X303166Y599583D03*
X298500Y622200D03*
X316500Y618500D03*
X288771Y637726D03*
X344616Y590187D03*
X320937Y582655D03*
X306766Y582469D03*
X339304Y709335D03*
X285773Y657061D03*
X294018Y655000D03*
X290500Y644700D03*
X286007Y692279D03*
X310000Y690500D03*
X345977Y684410D03*
X345671Y680190D03*
X303279Y670477D03*
X328723Y674658D03*
X334673Y672886D03*
X287600Y726400D03*
X418487Y71447D03*
X366300Y190000D03*
X374890Y177173D03*
X369882Y225923D03*
X358050Y254056D03*
X362349Y255239D03*
X357846Y260273D03*
X363100Y220900D03*
X382500Y339800D03*
X382800Y353300D03*
X392800Y491900D03*
X376544Y460678D03*
X364275Y486275D03*
X386000Y485700D03*
X397388Y479012D03*
X383600Y473500D03*
X380113Y480400D03*
X391129Y448629D03*
X372300Y478900D03*
X367552Y480084D03*
X385600Y537300D03*
X387517Y560556D03*
X391700Y507300D03*
X386400Y609500D03*
X357200Y592900D03*
X374522Y591597D03*
X383500Y588800D03*
X383400Y598800D03*
X379100Y588400D03*
X384025Y594525D03*
X383500Y604900D03*
X388700Y633400D03*
X384200Y626000D03*
X384495Y569100D03*
X383944Y573339D03*
X364900Y581500D03*
X380700Y684096D03*
X380800Y679800D03*
Y675600D03*
X381593Y694069D03*
X497137Y42455D03*
X450900Y29000D03*
Y24000D03*
X474400Y56600D03*
X468800Y57000D03*
X485585Y34890D03*
X451231Y41843D03*
X450832Y50121D03*
X485300Y27500D03*
X453400Y19100D03*
X477171Y51517D03*
X483347Y63650D03*
X493238Y52126D03*
X450200Y34416D03*
X448226Y45257D03*
X460442Y53761D03*
X484513Y22548D03*
X481353Y18104D03*
X498100Y34000D03*
X477129Y66151D03*
X460800Y66850D03*
X519493Y50899D03*
X519517Y55714D03*
X524672Y18026D03*
X515337Y20945D03*
X556300Y47148D03*
X545000Y63300D03*
X622364Y24999D03*
X618546Y50576D03*
X582232Y60757D03*
X598656Y30307D03*
X593347Y43217D03*
X621691Y40136D03*
X626700Y60200D03*
X598513Y57106D03*
X593247Y47907D03*
X593563Y24910D03*
X604047Y57707D03*
X609247Y63207D03*
X673140Y41600D03*
X695544Y21750D03*
X703300Y30100D03*
X697305Y28963D03*
X713200Y399200D03*
X712851Y483089D03*
X678474Y478005D03*
X710633Y463904D03*
X644559Y528060D03*
X729900Y26900D03*
X774200Y37200D03*
X781100Y19400D03*
X731437Y21928D03*
X718200Y399200D03*
X716100Y430500D03*
X721100D03*
X728900Y426800D03*
X720017Y483158D03*
X734761Y470838D03*
X852682Y74813D03*
X858373Y174835D03*
X842508Y145014D03*
X856468Y207064D03*
X853750Y181603D03*
X837195Y177710D03*
X856196Y212359D03*
X838169Y337936D03*
X801100Y398200D03*
X796100D03*
X845111Y362071D03*
X857706Y399786D03*
X852716Y399376D03*
X847820Y375672D03*
X830809Y371019D03*
X799000Y429500D03*
X804000D03*
X811800Y425800D03*
X811099Y481767D03*
X823728Y481512D03*
X903755Y100137D03*
X887928Y177932D03*
X894711Y187059D03*
X871261Y218621D03*
X882745Y369882D03*
X890963Y375283D03*
G54D119*
X665551Y527953D03*
X763976D03*
X747047D03*
X845472D03*
G54D54*
X134700Y697350D03*
G54D81*
X351285Y233565D03*
X365125D03*
G54D129*
X862772Y111138D03*
X887572D03*
X862772Y90638D03*
X887572D03*
X898101Y283208D03*
X873301D03*
X898101Y303708D03*
X873301D03*
G54D45*
X90854Y639150D03*
X98454D03*
X86983Y674124D03*
X94583D03*
X86983Y682024D03*
X94583D03*
X90854Y647050D03*
X98454D03*
X87900Y722700D03*
X95500D03*
X243324Y623114D03*
X250924D03*
X322740Y619400D03*
X330340D03*
X322740Y611500D03*
X330340D03*
X320774Y684270D03*
X328374D03*
X320774Y691970D03*
X328374D03*
X514972Y26680D03*
X522572D03*
X503854Y42093D03*
X511454D03*
X511465Y34432D03*
X503865D03*
X609257Y23971D03*
X616857D03*
X613247Y77407D03*
X620847D03*
X613247Y69307D03*
X620847D03*
X888313Y201350D03*
X895913D03*
X887184Y192800D03*
X894784D03*
X885492Y209135D03*
X893092D03*
X885492Y216835D03*
X893092D03*
X891166Y381316D03*
X883566D03*
G54D18*
X51000Y52000D03*
X62000D03*
X90768Y62255D03*
X101768D03*
X243199Y718747D03*
X232199D03*
X243199Y728347D03*
X232199D03*
X243199Y737947D03*
X232199D03*
X605847Y77007D03*
X594847D03*
G54D36*
X90157Y413582D03*
X309055Y157677D03*
G54D63*
X180190Y728775D03*
X158304D03*
G54D27*
X41452Y659909D03*
X179037Y463761D03*
X208200Y626900D03*
X145049Y687715D03*
X268300Y465400D03*
X254958Y589579D03*
X281370Y637250D03*
X246925Y633776D03*
X272203Y704337D03*
X274600Y640772D03*
X259500Y666000D03*
X347682Y189778D03*
X290095Y539294D03*
X316000Y526100D03*
X328200Y581394D03*
Y585000D03*
X385500Y541100D03*
X387411Y577031D03*
X366614Y639820D03*
X382500Y698000D03*
X375900Y710400D03*
X479426Y55778D03*
X489700Y38000D03*
X468786Y53022D03*
X549200Y61200D03*
X614247Y63107D03*
G54D72*
X346457Y57007D03*
X353543Y62913D03*
Y55039D03*
X346457Y66850D03*
Y74724D03*
Y84567D03*
X353543Y86535D03*
Y78661D03*
Y70787D03*
G54D90*
X421653Y126378D03*
X428740Y121654D03*
X421653Y130709D03*
X428740Y125985D03*
X421653Y136221D03*
X428740Y131496D03*
Y135827D03*
X421653Y183071D03*
Y140551D03*
Y144882D03*
X428740Y140158D03*
X421653Y150394D03*
X428740Y145670D03*
X421653Y154725D03*
X428740Y150000D03*
X421653Y159055D03*
X428740Y154331D03*
X421653Y164567D03*
X428740Y159843D03*
X421653Y168898D03*
X428740Y164173D03*
X421653Y173229D03*
X428740Y168504D03*
X421653Y178740D03*
X428740Y174016D03*
X435827Y126378D03*
X450000D03*
X464173D03*
X442913Y121654D03*
X457086D03*
X471260D03*
X435827Y130709D03*
X442913Y125985D03*
X450000Y130709D03*
X457086Y125985D03*
X464173Y130709D03*
X471260Y125985D03*
X435827Y136221D03*
X442913Y131496D03*
X450000Y136221D03*
X457086Y131496D03*
X464173Y136221D03*
X471260Y131496D03*
X442913Y135827D03*
X457086D03*
X471260D03*
X435827Y183071D03*
X450000D03*
X464173D03*
X435827Y140551D03*
X450000D03*
X464173D03*
X435827Y144882D03*
X442913Y140158D03*
X450000Y144882D03*
X457086Y140158D03*
X464173Y144882D03*
X471260Y140158D03*
X435827Y150394D03*
X442913Y145670D03*
X450000Y150394D03*
X457086Y145670D03*
X464173Y150394D03*
X471260Y145670D03*
X435827Y154725D03*
X442913Y150000D03*
X450000Y154725D03*
X457086Y150000D03*
X464173Y154725D03*
X471260Y150000D03*
X435827Y159055D03*
X442913Y154331D03*
X450000Y159055D03*
X457086Y154331D03*
X464173Y159055D03*
X471260Y154331D03*
X435827Y164567D03*
X442913Y159843D03*
X450000Y164567D03*
X457086Y159843D03*
X464173Y164567D03*
X471260Y159843D03*
X435827Y168898D03*
X442913Y164173D03*
X450000Y168898D03*
X457086Y164173D03*
X464173Y168898D03*
X471260Y164173D03*
X435827Y173229D03*
X442913Y168504D03*
X450000Y173229D03*
X457086Y168504D03*
X464173Y173229D03*
X471260Y168504D03*
X435827Y178740D03*
X442913Y174016D03*
X450000Y178740D03*
X457086Y174016D03*
X464173Y178740D03*
X471260Y174016D03*
X506693Y126378D03*
X520866D03*
X535039D03*
X549212D03*
X513779Y121654D03*
X527953D03*
X542126D03*
X556299D03*
X506693Y130709D03*
X513779Y125985D03*
X520866Y130709D03*
X527953Y125985D03*
X535039Y130709D03*
X542126Y125985D03*
X549212Y130709D03*
X556299Y125985D03*
X506693Y136221D03*
X513779Y131496D03*
X520866Y136221D03*
X527953Y131496D03*
X535039Y136221D03*
X542126Y131496D03*
X549212Y136221D03*
X556299Y131496D03*
X513779Y135827D03*
X527953D03*
X542126D03*
X556299D03*
X506693Y183071D03*
X520866D03*
X535039D03*
X549212D03*
X506693Y140551D03*
X520866D03*
X535039D03*
X549212D03*
X506693Y144882D03*
X513779Y140158D03*
X520866Y144882D03*
X527953Y140158D03*
X535039Y144882D03*
X542126Y140158D03*
X549212Y144882D03*
X556299Y140158D03*
X506693Y150394D03*
X513779Y145670D03*
X520866Y150394D03*
X527953Y145670D03*
X535039Y150394D03*
X542126Y145670D03*
X549212Y150394D03*
X556299Y145670D03*
X506693Y154725D03*
X513779Y150000D03*
X520866Y154725D03*
X527953Y150000D03*
X535039Y154725D03*
X542126Y150000D03*
X549212Y154725D03*
X556299Y150000D03*
X506693Y159055D03*
X513779Y154331D03*
X520866Y159055D03*
X527953Y154331D03*
X535039Y159055D03*
X542126Y154331D03*
X549212Y159055D03*
X556299Y154331D03*
X506693Y164567D03*
X513779Y159843D03*
X520866Y164567D03*
X527953Y159843D03*
X535039Y164567D03*
X542126Y159843D03*
X549212Y164567D03*
X556299Y159843D03*
X506693Y168898D03*
X513779Y164173D03*
X520866Y168898D03*
X527953Y164173D03*
X535039Y168898D03*
X542126Y164173D03*
X549212Y168898D03*
X556299Y164173D03*
X506693Y173229D03*
X513779Y168504D03*
X520866Y173229D03*
X527953Y168504D03*
X535039Y173229D03*
X542126Y168504D03*
X549212Y173229D03*
X556299Y168504D03*
X506693Y178740D03*
X513779Y174016D03*
X520866Y178740D03*
X527953Y174016D03*
X535039Y178740D03*
X542126Y174016D03*
X549212Y178740D03*
X556299Y174016D03*
G54D91*
X391358Y75749D03*
Y69149D03*
X387558D03*
Y75749D03*
G54D64*
X281645Y546834D03*
Y549394D03*
Y551954D03*
X274245D03*
Y549394D03*
Y546834D03*
G54D28*
X45052Y659909D03*
X182637Y463761D03*
X211800Y626900D03*
X148649Y687715D03*
X271900Y465400D03*
X258558Y589579D03*
X250525Y633776D03*
X275803Y704337D03*
X278200Y640772D03*
X263100Y666000D03*
X351282Y189778D03*
X293695Y539294D03*
X319600Y526100D03*
X284970Y637250D03*
X331800Y581394D03*
Y585000D03*
X389100Y541100D03*
X391011Y577031D03*
X370214Y639820D03*
X386100Y698000D03*
X379500Y710400D03*
X483026Y55778D03*
X493300Y38000D03*
X472386Y53022D03*
X552800Y61200D03*
X617847Y63107D03*
G54D37*
X108500Y482200D03*
X101113Y522777D03*
X101100Y515300D03*
X81032Y517477D03*
X81068Y509866D03*
X69778Y517477D03*
X69900Y510000D03*
X75405Y517477D03*
X75373Y509879D03*
X86673Y510000D03*
X92000Y517400D03*
X86659Y517477D03*
X93531Y496341D03*
X119600Y628800D03*
X117349Y697047D03*
X121449Y694247D03*
X113349Y697047D03*
X184924Y493148D03*
X157896Y519319D03*
X161902Y519349D03*
X142000Y515500D03*
X186537Y519381D03*
X182474Y520691D03*
X166280Y520400D03*
X170380D03*
X191400Y505800D03*
X194649Y520351D03*
X190600Y519400D03*
X178469Y521393D03*
X195500Y506200D03*
X174400Y516100D03*
X212000Y502700D03*
X186976Y636468D03*
X191076Y636598D03*
X170600Y637200D03*
X174700D03*
X178776Y636468D03*
X182876D03*
X153700Y626200D03*
X155849Y699115D03*
X211706Y641392D03*
X158349Y706915D03*
X225262Y518580D03*
X258969Y544921D03*
X247900Y616800D03*
X258000Y649664D03*
X232000Y642600D03*
X219200Y642200D03*
X271200Y676100D03*
X250800Y679300D03*
X262645Y708235D03*
X258500Y679200D03*
X238807Y658571D03*
X342497Y524061D03*
X345100Y539600D03*
X324500Y537200D03*
X320000D03*
X352480Y587564D03*
X286703Y618411D03*
X347680Y639664D03*
X387458Y74149D03*
X391458D03*
X360382Y193600D03*
X388489Y555935D03*
X378800Y583800D03*
X383000D03*
X356680Y589064D03*
X443457Y53415D03*
X594504Y60667D03*
X636647Y60307D03*
X723800Y33100D03*
Y25400D03*
X720017Y478614D03*
X716100Y438800D03*
X721100D03*
X842168Y188614D03*
X858622Y162514D03*
X850730Y357478D03*
X853060Y407698D03*
X823728Y477000D03*
X804000Y437800D03*
X799000D03*
G54D46*
X140090Y621027D03*
X202800Y510100D03*
X208100Y515200D03*
X208000Y520500D03*
X178800Y513400D03*
X160100Y622300D03*
X161900Y627800D03*
X167400Y618300D03*
X165800Y623700D03*
X206636Y618649D03*
X241100Y544100D03*
X238100Y550800D03*
X247300Y544000D03*
X235700Y544500D03*
X237980Y555707D03*
X217134Y521103D03*
X238168Y529269D03*
X235658Y534262D03*
X221898Y618622D03*
X235614Y609978D03*
X369100Y592006D03*
X740900Y553600D03*
X741000Y547700D03*
X830426Y482939D03*
X835949Y482890D03*
G54D55*
X154724Y537795D03*
Y540945D03*
Y544094D03*
X157874Y537795D03*
Y540945D03*
Y544094D03*
X161023Y537795D03*
Y540945D03*
Y544094D03*
X154724Y597638D03*
Y600787D03*
Y603937D03*
X157874Y597638D03*
Y600787D03*
Y603937D03*
X161023Y597638D03*
Y600787D03*
Y603937D03*
X214567Y537795D03*
Y540945D03*
Y544094D03*
X217716Y537795D03*
Y540945D03*
Y544094D03*
X220866Y537795D03*
Y540945D03*
Y544094D03*
X214567Y597638D03*
Y600787D03*
Y603937D03*
X217716Y597638D03*
Y600787D03*
Y603937D03*
X220866Y597638D03*
Y600787D03*
Y603937D03*
G54D82*
X305906Y388386D03*
G54D19*
G01X-36569Y-23804D02*
Y-103804D01*
G01D02*
X1258031D01*
G01X-40569Y-7804D02*
G02I-12000J0D01*
G01X-45719D02*
G02I-6850J0D01*
G01X-52569Y-23804D02*
Y8196D01*
G01X-36569Y-23804D02*
X1258031D01*
G01X-36569Y-59304D02*
X1258031D01*
G01X-36569Y-7804D02*
X-68569D01*
G01X470531Y-23804D02*
Y-103804D01*
G01X608031Y-23804D02*
Y-103804D01*
G01X723031Y-23804D02*
Y-103804D01*
G01X890531Y-23804D02*
Y-103804D01*
G01X1060531Y-23804D02*
Y-103804D01*
G01X1258031Y-23804D02*
Y-103804D01*
G01X1286031Y-7804D02*
G02I-12000J0D01*
G01X1280881D02*
G02I-6850J0D01*
G01X1274031Y-23804D02*
Y8196D01*
G01X1290031Y-7804D02*
X1258031D01*
X66435Y8514D03*
X61435D03*
X56435D03*
X51435D03*
X46435D03*
X41435D03*
X36435D03*
X31435D03*
X26435D03*
X21435D03*
X16435D03*
X8514Y10593D03*
Y15593D03*
Y20593D03*
Y25593D03*
Y30593D03*
Y35593D03*
Y40593D03*
Y45593D03*
Y50593D03*
Y55593D03*
Y60593D03*
Y65593D03*
Y70593D03*
Y75593D03*
Y80593D03*
Y85593D03*
Y90593D03*
Y95593D03*
Y100593D03*
Y105593D03*
Y110593D03*
Y115593D03*
Y120593D03*
Y125593D03*
Y130593D03*
Y135593D03*
Y140593D03*
Y145593D03*
Y150593D03*
Y155593D03*
Y160593D03*
Y165593D03*
Y170593D03*
Y175593D03*
Y180593D03*
Y185593D03*
Y190593D03*
Y195593D03*
Y200593D03*
Y205593D03*
Y210593D03*
Y215593D03*
Y220593D03*
Y225593D03*
Y230593D03*
Y235593D03*
Y240593D03*
Y245593D03*
Y250593D03*
Y255593D03*
Y260593D03*
Y265593D03*
Y270593D03*
Y275593D03*
Y280593D03*
Y285593D03*
Y290593D03*
Y295593D03*
Y300593D03*
Y305593D03*
Y310593D03*
Y315593D03*
Y320593D03*
Y325593D03*
Y330593D03*
Y335593D03*
Y340593D03*
Y345593D03*
Y350593D03*
Y355593D03*
Y360593D03*
Y365593D03*
Y370593D03*
Y375593D03*
Y380593D03*
Y385593D03*
Y390593D03*
Y395593D03*
Y400593D03*
Y405593D03*
Y410593D03*
Y415593D03*
Y420593D03*
Y425593D03*
Y430593D03*
Y435593D03*
Y440593D03*
Y445593D03*
Y450593D03*
Y455593D03*
Y460593D03*
Y465593D03*
Y470593D03*
Y475593D03*
Y480593D03*
Y485593D03*
Y490593D03*
Y495593D03*
Y500593D03*
Y505593D03*
Y510593D03*
Y515593D03*
Y520593D03*
Y525593D03*
Y530593D03*
Y535593D03*
Y540593D03*
Y545593D03*
Y550593D03*
Y555593D03*
Y560593D03*
Y565593D03*
Y570593D03*
Y575593D03*
Y580593D03*
Y585593D03*
Y590593D03*
Y595593D03*
Y600593D03*
Y605593D03*
Y610593D03*
Y615593D03*
Y620593D03*
Y625593D03*
Y630593D03*
Y635593D03*
Y640593D03*
Y645593D03*
Y650593D03*
Y655593D03*
Y660593D03*
Y665593D03*
Y670593D03*
Y675593D03*
Y680593D03*
Y685593D03*
Y690593D03*
Y695593D03*
Y700593D03*
Y705593D03*
Y710593D03*
Y715593D03*
Y720593D03*
X9942Y725256D03*
X12178Y729728D03*
X14414Y734200D03*
X16650Y738672D03*
X18886Y743144D03*
X21122Y747617D03*
X23358Y752089D03*
X111683Y63266D03*
Y58266D03*
Y23266D03*
Y18266D03*
Y13266D03*
X111435Y8514D03*
X106435D03*
X101435D03*
X96435D03*
X91435D03*
X86435D03*
X81435D03*
X76435D03*
X71435D03*
X111683Y118266D03*
Y113266D03*
Y108266D03*
Y103266D03*
Y98266D03*
Y93266D03*
Y88266D03*
Y83266D03*
Y78266D03*
Y73266D03*
Y68266D03*
Y203266D03*
Y198266D03*
Y193266D03*
Y188266D03*
Y183266D03*
Y178266D03*
Y173266D03*
Y168266D03*
Y163266D03*
Y158266D03*
Y153266D03*
Y148266D03*
Y278266D03*
Y273266D03*
Y268266D03*
Y263266D03*
Y258266D03*
Y253266D03*
Y248266D03*
Y243266D03*
Y238266D03*
Y233266D03*
Y228266D03*
Y223266D03*
Y218266D03*
Y213266D03*
Y208266D03*
Y348266D03*
Y343266D03*
Y338266D03*
Y333266D03*
Y328266D03*
Y323266D03*
Y318266D03*
Y313266D03*
Y308266D03*
Y303266D03*
Y298266D03*
Y293266D03*
Y288266D03*
Y283266D03*
Y418266D03*
Y413266D03*
Y408266D03*
Y403266D03*
Y398266D03*
Y393266D03*
Y388266D03*
Y383266D03*
Y378266D03*
Y373266D03*
Y368266D03*
Y363266D03*
Y358266D03*
Y353266D03*
X103940Y635460D03*
X76118Y625275D03*
X81118D03*
X86300Y703200D03*
X99337Y683756D03*
Y678756D03*
Y673756D03*
X86300Y708000D03*
X95200Y667500D03*
X90400D03*
X85600D03*
X76549Y680547D03*
Y675547D03*
X81549Y680547D03*
Y675547D03*
X134223Y691027D03*
X122335Y660582D03*
Y655782D03*
X76395Y755266D03*
X81395D03*
X86395D03*
X91395D03*
X96395D03*
X101395D03*
X106395D03*
X111395D03*
X116395D03*
X121395D03*
X126395D03*
X131395D03*
X136395D03*
X141395D03*
X108928Y744775D03*
X113928D03*
X118928D03*
X123928D03*
X103928D03*
X98928D03*
X93928D03*
X83125Y719240D03*
Y724040D03*
X196700Y704985D03*
X201700D03*
X206700D03*
X211700D03*
X191700D03*
X146395Y755266D03*
X151395D03*
X156395D03*
X161395D03*
X166395D03*
X171395D03*
X176395D03*
X181395D03*
X186395D03*
X191395D03*
X196395D03*
X201395D03*
X206395D03*
X211395D03*
X155400Y717700D03*
X221700Y704985D03*
X226700D03*
X216700D03*
X216395Y755266D03*
X221395D03*
X226395D03*
X231395D03*
X236395D03*
X241395D03*
X246395D03*
X251395D03*
X256395D03*
X261395D03*
X266395D03*
X271395D03*
X276395D03*
X281395D03*
X249200Y733700D03*
Y728700D03*
Y723700D03*
Y718700D03*
Y738500D03*
X330546Y8514D03*
X325546D03*
X320546D03*
X315546D03*
X310546D03*
X305546D03*
X300546D03*
X296034Y9002D03*
Y14002D03*
Y19002D03*
Y24002D03*
Y29002D03*
Y34002D03*
Y39002D03*
Y44002D03*
Y49002D03*
Y54002D03*
Y59002D03*
Y64002D03*
Y69002D03*
Y74002D03*
Y79002D03*
Y84002D03*
Y89002D03*
Y94002D03*
Y99002D03*
Y104002D03*
Y109002D03*
Y114002D03*
Y119002D03*
Y124002D03*
Y129002D03*
Y134002D03*
Y139002D03*
X334782Y184928D03*
X321182Y202574D03*
Y197774D03*
X305882Y195474D03*
X305382Y190174D03*
X334882Y195478D03*
Y200478D03*
Y190478D03*
X335061Y222578D03*
X335100Y218378D03*
X323492Y214234D03*
X305862Y210014D03*
X335000Y621200D03*
Y615400D03*
Y610200D03*
X325600Y640100D03*
X330400D03*
X335200D03*
X322000Y653081D03*
X312400D03*
X317200D03*
X307600D03*
X298700Y674600D03*
X303700D03*
X286395Y755266D03*
X291395D03*
X296395D03*
X301395D03*
X306395D03*
X311395D03*
X316395D03*
X321395D03*
X326395D03*
X331395D03*
X336395D03*
X315520Y711720D03*
X320320D03*
X325120D03*
X305559Y720973D03*
X310559D03*
X305559Y725973D03*
X310559D03*
X299500Y725400D03*
X373073Y201889D03*
X399754Y706071D03*
X389168Y743572D03*
X391404Y739100D03*
X393640Y734628D03*
X395876Y730156D03*
X398112Y725684D03*
X399754Y716071D03*
Y711071D03*
X435000Y29000D03*
X438500Y25500D03*
Y32500D03*
X491500Y71600D03*
X496500D03*
X491500Y76600D03*
X496500D03*
X556510Y53626D03*
X516693Y46345D03*
X521493D03*
X516693Y41545D03*
X521493D03*
Y36745D03*
X516693D03*
X521493Y31945D03*
X526530Y43775D03*
X516693Y31945D03*
X567700Y28240D03*
X548550Y76480D03*
X525000Y76300D03*
X525200Y80900D03*
X556710Y64726D03*
X543750Y76480D03*
X506500Y76600D03*
X501500D03*
Y71600D03*
X608847Y34607D03*
X614032Y33307D03*
X621747Y63307D03*
X626647Y77507D03*
Y72507D03*
Y67507D03*
X593017Y69796D03*
X588217Y74596D03*
Y69796D03*
X576624Y193205D03*
Y198205D03*
Y203205D03*
Y208205D03*
Y213205D03*
Y223205D03*
Y228205D03*
Y233205D03*
Y238205D03*
Y243205D03*
Y248205D03*
Y253205D03*
Y258205D03*
Y263205D03*
Y268205D03*
Y273205D03*
Y278205D03*
Y333205D03*
Y338205D03*
Y343205D03*
Y348205D03*
Y353205D03*
Y358205D03*
Y363205D03*
Y368205D03*
Y373205D03*
Y378205D03*
Y383205D03*
Y388205D03*
Y393205D03*
Y398205D03*
Y403205D03*
Y408205D03*
Y413205D03*
Y418205D03*
Y423205D03*
Y428205D03*
Y433205D03*
Y438205D03*
Y443205D03*
Y448205D03*
Y498205D03*
Y503205D03*
Y508205D03*
Y513205D03*
Y518205D03*
Y523205D03*
Y528205D03*
Y533205D03*
Y538205D03*
Y543205D03*
Y548205D03*
Y553205D03*
Y558205D03*
Y563205D03*
Y568205D03*
Y573205D03*
Y578205D03*
Y583205D03*
Y588205D03*
X578710Y592712D03*
X580946Y597184D03*
X583182Y601656D03*
X585418Y606129D03*
X587654Y610601D03*
X635975Y621407D03*
X640975D03*
X715546Y8514D03*
X710546D03*
X705546D03*
X700546D03*
X695546D03*
X668847Y27107D03*
X663847D03*
X658847D03*
X653847D03*
X653601Y46761D03*
X658601D03*
X653601Y51761D03*
X658601D03*
X663601Y46761D03*
Y51761D03*
X668601Y46761D03*
Y51761D03*
X700065Y135985D03*
Y125985D03*
Y115985D03*
X710065D03*
Y125985D03*
Y135985D03*
X649590Y114036D03*
X700065Y155985D03*
X710065D03*
Y145985D03*
X696159Y225829D03*
X698909Y278104D03*
X700065Y265985D03*
Y255985D03*
Y245985D03*
Y235985D03*
X710065D03*
Y245985D03*
Y255985D03*
Y265985D03*
X709625Y275991D03*
X710065Y325985D03*
Y315985D03*
X711574Y285985D03*
X708307Y295429D03*
X710065Y305985D03*
Y335985D03*
Y345985D03*
X700065Y385985D03*
Y395985D03*
Y405985D03*
Y415985D03*
X710065Y375985D03*
Y355985D03*
Y365985D03*
Y455985D03*
X684399Y466984D03*
Y471984D03*
X663500Y484000D03*
Y489000D03*
Y494000D03*
X692282Y476720D03*
X689875Y464586D03*
X698275Y438305D03*
X683100Y485200D03*
X679832Y494100D03*
Y489100D03*
X679100Y483300D03*
X674900D03*
X674832Y489100D03*
Y494100D03*
X682800Y480700D03*
X693392Y520482D03*
X683392D03*
X688392D03*
X705080Y521247D03*
X694272Y495786D03*
X645975Y621407D03*
X650975D03*
X655975D03*
X660975D03*
X665975D03*
X670975D03*
X675975D03*
X680975D03*
X685975D03*
X690975D03*
X695975D03*
X700975D03*
X705975D03*
X710975D03*
X715975D03*
X785546Y8514D03*
X780546D03*
X775546D03*
X770546D03*
X765546D03*
X760546D03*
X755546D03*
X750546D03*
X745546D03*
X740546D03*
X735546D03*
X730546D03*
X725546D03*
X720546D03*
X770065Y55985D03*
Y65985D03*
Y75985D03*
X750065Y85985D03*
X770065D03*
X760065D03*
X740065D03*
X730065Y95985D03*
X760065D03*
X780065D03*
X770065D03*
Y105985D03*
X780065D03*
Y115985D03*
X730065Y135985D03*
Y125985D03*
Y115985D03*
Y105985D03*
X750065Y95985D03*
X740065D03*
X750065Y105985D03*
X760065D03*
X740065D03*
X750065Y115985D03*
X760065D03*
X770065D03*
X740065D03*
X750065Y125985D03*
X760065D03*
X770065D03*
X780065D03*
X740065D03*
X750065Y135985D03*
X760065D03*
X770065D03*
X780065D03*
X740065D03*
X720065Y105985D03*
Y115985D03*
Y125985D03*
Y135985D03*
Y155985D03*
X780065D03*
X730065D03*
Y145985D03*
X750065D03*
X760065D03*
X770065D03*
X780065D03*
X740065D03*
X750065Y155985D03*
X760065D03*
X770065D03*
X740065D03*
X750065Y165985D03*
X760065D03*
X770065D03*
X740065D03*
X750065Y175985D03*
X760065D03*
X770065D03*
X740065D03*
X750065Y185985D03*
X760065D03*
X770065D03*
X740065D03*
X750065Y195985D03*
X760065D03*
X770065D03*
X740065D03*
X750065Y205985D03*
X760065D03*
X770065D03*
X740065D03*
X720065Y145985D03*
X730065Y215985D03*
X773469Y277001D03*
X780065Y275985D03*
X787817Y275879D03*
X750065Y215985D03*
X760065D03*
X770065D03*
X780065D03*
X740065D03*
X780065Y265985D03*
Y255985D03*
Y245985D03*
Y235985D03*
Y225985D03*
X770065Y265985D03*
Y255985D03*
Y245985D03*
Y235985D03*
Y225985D03*
X763133Y275881D03*
X759790Y263326D03*
X760065Y255985D03*
Y245985D03*
Y235985D03*
Y225985D03*
X750065Y275985D03*
Y265985D03*
Y255985D03*
Y245985D03*
Y235985D03*
Y225985D03*
X741608Y277171D03*
X740065Y265985D03*
Y255985D03*
Y245985D03*
Y235985D03*
Y225985D03*
X730830Y276087D03*
X730065Y265985D03*
Y255985D03*
X731766Y246017D03*
X730065Y235985D03*
X730190Y223549D03*
X720237Y223228D03*
X720065Y235985D03*
X721766Y246017D03*
X720065Y255985D03*
Y265985D03*
X718617Y275736D03*
X770065Y335985D03*
X760065D03*
X720065Y325985D03*
X760065D03*
X750065D03*
X740065D03*
X730065D03*
X720065Y315985D03*
X780065Y285985D03*
X770065D03*
X760065D03*
X750065Y295985D03*
X760065D03*
X770065D03*
X780065D03*
Y305985D03*
Y315985D03*
Y325985D03*
Y335985D03*
Y345985D03*
X770065Y305985D03*
Y315985D03*
Y325985D03*
Y345985D03*
X760065Y305985D03*
Y315985D03*
Y345985D03*
X750065Y305985D03*
Y315985D03*
Y335985D03*
Y345985D03*
X740065Y305985D03*
Y315985D03*
Y335985D03*
Y345985D03*
X730065D03*
Y335985D03*
Y315985D03*
X752500Y286000D03*
X740065Y295985D03*
X741000Y286000D03*
X730065Y305985D03*
X729486Y296094D03*
X729294Y285987D03*
X721574Y285985D03*
X719049Y296011D03*
X720065Y305985D03*
Y335985D03*
Y345985D03*
X750065Y415985D03*
X760065D03*
X770065D03*
X780065D03*
X730065D03*
X740065D03*
X750065Y405985D03*
X760065D03*
X770065D03*
X780065D03*
X730065D03*
X740065D03*
X780065Y395985D03*
X770065D03*
X760065D03*
X750065D03*
X740065D03*
X730065D03*
X720065Y375985D03*
X730065Y365985D03*
Y375985D03*
Y385985D03*
X750065D03*
X760065D03*
X770065D03*
X780065D03*
X740065D03*
X750065Y375985D03*
X760065D03*
X770065D03*
X780065D03*
X740065D03*
X750065Y365985D03*
X760065D03*
X770065D03*
X780065D03*
X740065D03*
X780065Y355985D03*
X770065D03*
X760065D03*
X750065D03*
X740065D03*
X730065D03*
X720065D03*
Y365985D03*
Y455985D03*
Y465985D03*
X750065D03*
X760065D03*
X770065D03*
X780065D03*
X730065D03*
X740065D03*
X780065Y455985D03*
X770065D03*
X760065D03*
X750065D03*
X740065D03*
X730065D03*
X750065Y445985D03*
X760065D03*
X770065D03*
X780065D03*
X730065D03*
X740065D03*
X750065Y435985D03*
X760065D03*
X770065D03*
X780065D03*
X740065D03*
X750065Y425985D03*
X760065D03*
X770065D03*
X780065D03*
X736217Y493664D03*
X776658Y489380D03*
X771658D03*
X781658D03*
Y494380D03*
X741217Y493664D03*
X776658Y494380D03*
X771658D03*
X784604Y519082D03*
X758512Y534430D03*
X747107Y536580D03*
X739334Y524156D03*
X752602Y517850D03*
X736580Y507734D03*
X788015Y507785D03*
X783015D03*
X747602Y517850D03*
X731580Y507734D03*
X716578Y509762D03*
X721590Y511659D03*
X726590D03*
X720975Y621407D03*
X725975D03*
X730975D03*
X735975D03*
X740975D03*
X745975D03*
X750975D03*
X755975D03*
X760975D03*
X765975D03*
X770975D03*
X775975D03*
X780975D03*
X785975D03*
X850546Y8514D03*
X845546D03*
X840546D03*
X835546D03*
X830546D03*
X825546D03*
X820546D03*
X815546D03*
X810546D03*
X805546D03*
X800546D03*
X795546D03*
X790546D03*
X820065Y105985D03*
Y135985D03*
Y125985D03*
Y115985D03*
X810065Y135985D03*
Y125985D03*
Y115985D03*
X790065Y105985D03*
X800065Y115985D03*
X790065D03*
Y125985D03*
X800065D03*
Y135985D03*
X790065D03*
X853436Y108917D03*
Y113717D03*
X853435Y90260D03*
Y95060D03*
X820065Y155985D03*
X810065D03*
X800065D03*
X790065D03*
X820065Y145985D03*
X810065D03*
X790065D03*
X800065D03*
X820313Y276188D03*
X810065Y275985D03*
X800065D03*
X820065Y265985D03*
Y255985D03*
Y245985D03*
Y235985D03*
Y225985D03*
X810065Y265985D03*
Y255985D03*
Y245985D03*
Y235985D03*
X800065Y265985D03*
Y255985D03*
Y245985D03*
Y235985D03*
X790065Y265985D03*
Y255985D03*
Y245985D03*
Y235985D03*
Y225985D03*
X857965Y273150D03*
X820065Y305985D03*
Y295985D03*
Y285985D03*
X810065Y295985D03*
Y285985D03*
X800065D03*
X790065D03*
Y295985D03*
X800065D03*
X810065Y305985D03*
X810000Y314000D03*
X810065Y325985D03*
X800065Y305985D03*
Y315985D03*
Y325985D03*
Y335985D03*
Y345985D03*
X790065Y305985D03*
Y315985D03*
Y325985D03*
X791500Y336000D03*
X790065Y345985D03*
X859407Y300314D03*
Y309914D03*
Y305114D03*
Y295314D03*
Y290314D03*
Y285314D03*
X790065Y415985D03*
Y405985D03*
Y395985D03*
Y375985D03*
X800065D03*
X790065Y365985D03*
X800065D03*
Y355985D03*
X790065D03*
X800065Y455985D03*
Y465985D03*
X790065D03*
Y455985D03*
Y445985D03*
Y435985D03*
X790191Y426486D03*
X809000Y429400D03*
X840057Y494320D03*
X835057D03*
X805771Y518743D03*
X789604Y519082D03*
X794604D03*
X836023Y508124D03*
X825161Y507954D03*
X820161D03*
X815161D03*
X805983Y508293D03*
X793015Y507785D03*
X790975Y621407D03*
X795975D03*
X800975D03*
X805975D03*
X810975D03*
X815975D03*
X820975D03*
X825975D03*
X830975D03*
X835975D03*
X840975D03*
X854971Y637313D03*
Y642313D03*
Y647313D03*
Y652313D03*
Y657313D03*
Y662313D03*
Y667313D03*
Y672313D03*
Y677313D03*
Y682313D03*
Y687313D03*
Y692313D03*
Y697313D03*
Y702313D03*
Y707313D03*
Y712313D03*
X916683Y62377D03*
Y57377D03*
Y52377D03*
Y47377D03*
Y42377D03*
Y37377D03*
Y32377D03*
Y27377D03*
Y22377D03*
Y17377D03*
X915546Y8514D03*
X910546D03*
X905546D03*
X900546D03*
X883222Y59214D03*
X888022D03*
X892822D03*
X897622D03*
X880922Y63714D03*
X885722D03*
X890522D03*
X895322D03*
X900122D03*
X916683Y132377D03*
Y127377D03*
Y122377D03*
Y117377D03*
Y112377D03*
Y107377D03*
Y102377D03*
Y97377D03*
Y92377D03*
Y87377D03*
Y82377D03*
Y77377D03*
Y72377D03*
Y67377D03*
X897250Y81510D03*
X902050D03*
Y86310D03*
X897250D03*
Y91110D03*
X902050D03*
X897250Y95910D03*
X902050D03*
X916683Y207377D03*
Y202377D03*
Y197377D03*
Y192377D03*
Y187377D03*
Y182377D03*
Y177377D03*
Y172377D03*
Y167377D03*
Y162377D03*
Y157377D03*
Y152377D03*
Y147377D03*
Y142377D03*
Y137377D03*
X900600Y201239D03*
X897803Y207684D03*
X902803D03*
X880222Y206781D03*
X875222D03*
X916683Y277377D03*
Y272377D03*
Y267377D03*
Y262377D03*
Y257377D03*
Y252377D03*
Y247377D03*
Y242377D03*
Y237377D03*
Y232377D03*
Y227377D03*
Y222377D03*
Y217377D03*
Y212377D03*
X897195Y275688D03*
X902195D03*
Y270688D03*
X897195D03*
X897803Y217684D03*
Y212684D03*
X902803Y217684D03*
Y212684D03*
X896031Y228468D03*
Y223468D03*
X891031D03*
Y228468D03*
Y238468D03*
X896031D03*
X891031Y233468D03*
X896031D03*
X868376Y271313D03*
X873376D03*
X880122Y216781D03*
X875122D03*
X880222Y211781D03*
X875222D03*
X916683Y347377D03*
Y342377D03*
Y337377D03*
Y332377D03*
Y327377D03*
Y322377D03*
Y317377D03*
Y312377D03*
Y307377D03*
Y302377D03*
Y297377D03*
Y292377D03*
Y287377D03*
Y282377D03*
X896030Y296330D03*
X901030D03*
X900995Y290712D03*
X895995D03*
X900819Y316367D03*
X895819D03*
X900716Y311058D03*
X895716D03*
X864207Y300314D03*
Y309914D03*
Y305114D03*
Y295314D03*
Y290314D03*
Y285314D03*
X916683Y422377D03*
Y417377D03*
Y412377D03*
Y407377D03*
Y402377D03*
Y397377D03*
Y392377D03*
Y387377D03*
Y382377D03*
Y377377D03*
Y372377D03*
Y367377D03*
Y362377D03*
Y357377D03*
Y352377D03*
X876451Y407949D03*
X880665Y410841D03*
X885665D03*
X890665D03*
X895665D03*
X900665D03*
X902091Y369397D03*
X897091D03*
X902091Y374397D03*
X897091D03*
Y379397D03*
X902091D03*
X888548Y392923D03*
X883548D03*
X893548D03*
X888548Y387923D03*
X893548D03*
X883548D03*
X916683Y492377D03*
Y487377D03*
Y482377D03*
Y477377D03*
Y472377D03*
Y467377D03*
Y462377D03*
Y457377D03*
Y452377D03*
Y447377D03*
Y442377D03*
Y437377D03*
Y432377D03*
Y427377D03*
Y562377D03*
Y557377D03*
Y552377D03*
Y547377D03*
Y542377D03*
Y537377D03*
Y532377D03*
Y527377D03*
Y522377D03*
Y517377D03*
Y512377D03*
Y507377D03*
Y502377D03*
Y497377D03*
Y637377D03*
Y632377D03*
Y627377D03*
Y622377D03*
Y617377D03*
Y612377D03*
Y607377D03*
Y602377D03*
Y597377D03*
Y592377D03*
Y587377D03*
Y582377D03*
Y577377D03*
Y572377D03*
Y567377D03*
Y707377D03*
Y702377D03*
Y697377D03*
Y692377D03*
Y687377D03*
Y682377D03*
Y677377D03*
Y672377D03*
Y667377D03*
Y662377D03*
Y657377D03*
Y652377D03*
Y647377D03*
Y642377D03*
X901041Y753684D03*
X903277Y749212D03*
X905513Y744740D03*
X907749Y740268D03*
X909985Y735796D03*
X912221Y731323D03*
X914457Y726851D03*
X916683Y722377D03*
Y717377D03*
Y712377D03*
G54D73*
X339331Y49803D03*
X360669Y91929D03*
G54D29*
X64884Y643900D03*
X48284Y671800D03*
X211750Y634100D03*
X210500Y630600D03*
X148700Y691600D03*
X147417Y740048D03*
X275620Y715620D03*
X287000Y531100D03*
X305670Y612350D03*
X322300Y599000D03*
X288495Y576463D03*
X294804Y688120D03*
X286170Y644150D03*
X374104Y197291D03*
X362586Y639880D03*
X446135Y34357D03*
X707700Y423800D03*
X790600Y422800D03*
G54D56*
X169149Y691815D03*
X357882Y185174D03*
X450488Y54522D03*
X433255Y47144D03*
X433257Y42488D03*
X433246Y51800D03*
X579304Y45967D03*
X603447Y30307D03*
X781400Y29800D03*
X840322Y160314D03*
X848622Y145014D03*
X844706Y340240D03*
X820768Y371019D03*
G54D74*
X339331Y91929D03*
X360669Y49803D03*
G54D83*
X355739Y565469D03*
Y562909D03*
Y560349D03*
Y557789D03*
Y555229D03*
Y552669D03*
Y550109D03*
Y547549D03*
X321324Y564683D03*
Y562123D03*
Y559563D03*
Y557003D03*
Y554443D03*
X299124D03*
Y557003D03*
Y559563D03*
Y562123D03*
Y564683D03*
X355739Y575709D03*
Y573149D03*
Y570589D03*
Y568029D03*
X321324Y577483D03*
Y574923D03*
Y572363D03*
Y569803D03*
Y567243D03*
X299124D03*
Y569803D03*
Y572363D03*
Y574923D03*
Y577483D03*
X352100Y673680D03*
Y676240D03*
Y678800D03*
Y681360D03*
Y683920D03*
Y686480D03*
Y689040D03*
Y691600D03*
Y694160D03*
Y696720D03*
X377939Y547549D03*
Y550109D03*
Y552669D03*
Y555229D03*
Y557789D03*
Y560349D03*
Y562909D03*
Y565469D03*
Y568029D03*
Y570589D03*
Y573149D03*
Y575709D03*
X374300Y696720D03*
Y694160D03*
Y691600D03*
Y689040D03*
Y686480D03*
Y683920D03*
Y681360D03*
Y678800D03*
Y676240D03*
Y673680D03*
G54D92*
X372000Y71800D03*
G54D38*
X108500Y478800D03*
X93531Y492941D03*
X101113Y519377D03*
X101100Y511900D03*
X81032Y514077D03*
X81068Y506466D03*
X69778Y514077D03*
X69900Y506600D03*
X75405Y514077D03*
X75373Y506479D03*
X86673Y506600D03*
X92000Y514000D03*
X86659Y514077D03*
X119600Y625400D03*
X117349Y693647D03*
X121449Y690847D03*
X113349Y693647D03*
X184924Y489748D03*
X157896Y515919D03*
X161902Y515949D03*
X142000Y512100D03*
X186537Y515981D03*
X182474Y517291D03*
X166280Y517000D03*
X170380D03*
X191400Y502400D03*
X194649Y516951D03*
X190600Y516000D03*
X178469Y517993D03*
X195500Y502800D03*
X174400Y512700D03*
X212000Y499300D03*
X211706Y637992D03*
X186976Y633068D03*
X191076Y633198D03*
X170600Y633800D03*
X174700D03*
X178776Y633068D03*
X182876D03*
X153700Y622800D03*
X155849Y695715D03*
X158349Y703515D03*
X225262Y515180D03*
X258969Y541521D03*
X247900Y613400D03*
X258000Y646264D03*
X232000Y639200D03*
X219200Y638800D03*
X271200Y672700D03*
X250800Y675900D03*
X262645Y704835D03*
X258500Y675800D03*
X238807Y655171D03*
X342497Y520661D03*
X345100Y536200D03*
X324500Y533800D03*
X320000D03*
X347680Y636264D03*
X352480Y584164D03*
X286703Y615011D03*
X387458Y70749D03*
X391458D03*
X360382Y190200D03*
X388489Y552535D03*
X378800Y580400D03*
X383000D03*
X356680Y585664D03*
X443457Y50015D03*
X594504Y57267D03*
X636647Y56907D03*
X723800Y29700D03*
Y22000D03*
X720017Y475214D03*
X716100Y435400D03*
X721100D03*
X842168Y185214D03*
X858622Y159114D03*
X850730Y354078D03*
X853060Y404298D03*
X823728Y473600D03*
X804000Y434400D03*
X799000D03*
G54D47*
X131900Y624300D03*
X340034Y112312D03*
X345034D03*
X370220Y580786D03*
X509055Y22402D03*
X504381Y22399D03*
X631781Y57411D03*
G54D65*
X250624Y629614D03*
X786900Y25000D03*
X851620Y366572D03*
X866768Y210564D03*
X863120Y405672D03*
G54D39*
X124290Y490300D03*
Y485300D03*
Y480300D03*
Y475300D03*
Y470300D03*
Y465300D03*
Y460300D03*
Y495300D03*
X161440Y460300D03*
Y465300D03*
Y470300D03*
Y475300D03*
Y480300D03*
Y485300D03*
Y490300D03*
Y495300D03*
X258375Y460300D03*
Y465300D03*
Y470300D03*
Y475300D03*
Y480300D03*
Y485300D03*
Y490300D03*
X221225D03*
Y485300D03*
Y480300D03*
Y475300D03*
Y470300D03*
Y465300D03*
Y460300D03*
X258375Y495300D03*
X221225D03*
X267600Y582000D03*
Y587000D03*
Y592000D03*
Y597000D03*
X287600D03*
Y592000D03*
Y587000D03*
Y582000D03*
X379088Y537881D03*
Y532881D03*
Y527881D03*
Y522881D03*
X359088D03*
Y527881D03*
Y532881D03*
Y537881D03*
G54D84*
X298219Y527239D03*
Y529209D03*
Y531179D03*
Y533149D03*
X307419D03*
Y531179D03*
Y529209D03*
Y527239D03*
X377739Y515004D03*
Y513039D03*
Y511069D03*
Y509099D03*
Y507134D03*
X361439D03*
Y509099D03*
Y511069D03*
Y513039D03*
Y515004D03*
G54D75*
X354000Y119740D03*
Y116000D03*
Y112260D03*
X357800Y706700D03*
Y702960D03*
Y710440D03*
X363000Y112260D03*
Y119740D03*
X366800Y702960D03*
Y710440D03*
G54D48*
X131900Y629900D03*
X340034Y117912D03*
X345034D03*
X370220Y586386D03*
X509055Y28002D03*
X504381Y27999D03*
X631781Y63011D03*
G54D66*
X245024Y629614D03*
X781300Y25000D03*
X857520Y405672D03*
X846020Y366572D03*
X861168Y210564D03*
G54D93*
X372000Y68800D03*
G54D57*
X174749Y691815D03*
X363482Y185174D03*
X456088Y54522D03*
X438855Y47144D03*
X438857Y42488D03*
X438846Y51800D03*
X584904Y45967D03*
X609047Y30307D03*
X787000Y29800D03*
X845922Y160314D03*
X854222Y145014D03*
X850306Y340240D03*
X826368Y371019D03*
G54D49*
X119400Y638900D03*
X123100D03*
X207900Y637900D03*
X215406Y637892D03*
X228200Y639100D03*
X282600Y682100D03*
X258000Y653700D03*
X297767Y582318D03*
X294167D03*
X336631Y681726D03*
X370650Y190014D03*
X364600Y491900D03*
X849625Y177677D03*
X842984Y370969D03*
X893974Y179135D03*
X890639Y367560D03*
X878439Y400923D03*
G54D58*
X197087Y679921D03*
G54D94*
X372000Y65400D03*
G54D67*
X251091Y692774D03*
X248531D03*
X245971D03*
Y686274D03*
X251091D03*
X271240Y686350D03*
X273800D03*
X276360D03*
Y692850D03*
X271240D03*
X263491Y692574D03*
X260931D03*
X258371D03*
Y686074D03*
X263491D03*
X363975Y203549D03*
X369095D03*
Y210049D03*
X366535D03*
X363975D03*
X370140Y487250D03*
X372700D03*
X375260D03*
Y493750D03*
X370140D03*
G54D85*
X312262Y593351D03*
Y590791D03*
Y588231D03*
X318762D03*
Y593351D03*
X337750Y591440D03*
Y594000D03*
Y596560D03*
X331250D03*
Y591440D03*
G54D76*
X350737Y104200D03*
X372770Y52800D03*
Y48200D03*
X372470Y86300D03*
Y81700D03*
G54D86*
X353514Y604746D03*
Y620494D03*
X376814D03*
Y604746D03*
G54D95*
X357290Y624270D03*
X373038D03*
Y600970D03*
X357290D03*
G54D77*
X353737Y104200D03*
X375770Y52800D03*
Y48200D03*
X375470Y86300D03*
Y81700D03*
G54D68*
X244750Y666500D03*
X252250Y662625D03*
Y670375D03*
X244750Y652500D03*
X252250Y656375D03*
Y648625D03*
X361509Y175844D03*
X369009Y171969D03*
Y179719D03*
G54D59*
X201801Y684252D03*
X225601D03*
X724200Y398380D03*
X807100Y397380D03*
G54D78*
X356611Y199968D03*
X351611D03*
X346611D03*
X341611D03*
Y219968D03*
X346611D03*
X351611D03*
X356611D03*
G54D87*
X353864Y606714D03*
Y608683D03*
Y610651D03*
Y612620D03*
Y614589D03*
Y616557D03*
Y618526D03*
X376464D03*
Y616557D03*
Y614589D03*
Y612620D03*
Y610651D03*
Y608683D03*
Y606714D03*
G54D96*
X359258Y623920D03*
X361227D03*
X363195D03*
X365164D03*
X367133D03*
X369101D03*
X371070D03*
Y601320D03*
X369101D03*
X367133D03*
X365164D03*
X363195D03*
X361227D03*
X359258D03*
G54D69*
X230315Y679921D03*
G54D97*
X365164Y612620D03*
G54D79*
X297146Y205315D03*
Y202165D03*
Y199016D03*
Y195866D03*
Y192717D03*
X314666Y205315D03*
Y202165D03*
Y199016D03*
Y195866D03*
Y192717D03*
X297146Y277756D03*
Y274606D03*
Y271457D03*
Y268307D03*
Y265158D03*
Y262008D03*
Y258858D03*
Y255709D03*
Y252559D03*
Y249410D03*
Y246260D03*
Y243110D03*
Y239961D03*
Y236811D03*
Y233661D03*
Y230512D03*
Y227362D03*
Y224213D03*
Y221063D03*
Y217913D03*
Y214764D03*
Y211614D03*
Y208465D03*
X314666Y277756D03*
Y274606D03*
Y271457D03*
Y268307D03*
Y265158D03*
Y262008D03*
Y258858D03*
Y255709D03*
Y252559D03*
Y249410D03*
Y246260D03*
Y243110D03*
Y239961D03*
Y236811D03*
Y233661D03*
Y230512D03*
Y227362D03*
Y224213D03*
Y221063D03*
Y217913D03*
Y214764D03*
Y211614D03*
Y208465D03*
X297146Y350197D03*
Y347047D03*
Y343898D03*
Y340748D03*
Y337599D03*
Y334449D03*
Y331299D03*
Y328150D03*
Y325000D03*
Y321850D03*
Y318701D03*
Y315551D03*
Y312402D03*
Y309252D03*
Y306102D03*
Y302953D03*
Y299803D03*
Y296654D03*
Y293504D03*
Y290354D03*
Y287205D03*
Y284055D03*
Y280906D03*
X314666Y350197D03*
Y347047D03*
Y343898D03*
Y340748D03*
Y337599D03*
Y334449D03*
Y331299D03*
Y328150D03*
Y325000D03*
Y321850D03*
Y318701D03*
Y315551D03*
Y312402D03*
Y309252D03*
Y306102D03*
Y302953D03*
Y299803D03*
Y296654D03*
Y293504D03*
Y290354D03*
Y287205D03*
Y284055D03*
Y280906D03*
X297146Y378543D03*
Y375394D03*
Y372244D03*
Y369095D03*
Y365945D03*
Y362795D03*
Y359646D03*
Y356496D03*
Y353347D03*
X314666Y378543D03*
Y375394D03*
Y372244D03*
Y369095D03*
Y365945D03*
Y362795D03*
Y359646D03*
Y356496D03*
Y353347D03*
G54D88*
X328600Y665850D03*
X324725Y658350D03*
X332475D03*
G54D98*
X369273Y645871D03*
X360049D03*
Y651827D03*
X369273D03*
G54D89*
X372000Y62400D03*
G54D99*
X461110Y45450D03*
X474890D03*
Y25350D03*
X461110D03*
X603051Y51073D03*
X608957D03*
Y38861D03*
X603051D03*
M02*
